(kicad_sch
	(version 20250114)
	(generator "eeschema")
	(generator_version "9.0")
	(paper "A3")
	(title_block
		(title "RDIMM DDR5 Tester")
		(date "2026-05-21")
		(rev "2.2.0")
		(company "Antmicro")
		(comment 1 "www.antmicro.com")
		(comment 2 "Antmicro")
	)
	(text "Power source"
		(exclude_from_sim no)
		(at 13.97 25.4 0)
		(effects
			(font
				(size 2 2)
				(thickness 0.4)
				(bold yes)
			)
			(justify left bottom)
		)
	)
	(text "I2C: 0x50, 0x58"
		(exclude_from_sim no)
		(at 251.968 272.288 0)
		(effects
			(font
				(size 1.27 1.27)
			)
			(justify left bottom)
		)
	)
	(text "VREF DAC"
		(exclude_from_sim no)
		(at 154.94 71.12 0)
		(effects
			(font
				(size 2 2)
				(thickness 0.4)
				(bold yes)
			)
			(justify left bottom)
		)
	)
	(text "I2C: 0x60"
		(exclude_from_sim no)
		(at 208.28 106.68 0)
		(effects
			(font
				(size 1.27 1.27)
			)
			(justify left bottom)
		)
	)
	(text "Max 10W"
		(exclude_from_sim no)
		(at 373.38 85.725 0)
		(effects
			(font
				(size 1.27 1.27)
			)
			(justify left bottom)
		)
	)
	(text "7-15V"
		(exclude_from_sim no)
		(at 33.02 54.61 0)
		(effects
			(font
				(size 1.27 1.27)
			)
			(justify left bottom)
		)
	)
	(text "Power supply sequencer"
		(exclude_from_sim no)
		(at 252.73 125.73 0)
		(effects
			(font
				(size 2 2)
				(thickness 0.4)
				(bold yes)
			)
			(justify left bottom)
		)
	)
	(text "Always-ON +3V3 LDO"
		(exclude_from_sim no)
		(at 152.4 19.05 0)
		(effects
			(font
				(size 2 2)
				(thickness 0.4)
				(bold yes)
			)
			(justify left bottom)
		)
	)
	(text "Power cycle "
		(exclude_from_sim no)
		(at 153.67 125.73 0)
		(effects
			(font
				(size 2 2)
				(thickness 0.4)
				(bold yes)
			)
			(justify left bottom)
		)
	)
	(text "Config switch"
		(exclude_from_sim no)
		(at 15.24 199.39 0)
		(effects
			(font
				(size 2 2)
				(thickness 0.4)
				(bold yes)
			)
			(justify left bottom)
		)
	)
	(text "140ms delay\nfixed"
		(exclude_from_sim no)
		(at 207.645 198.755 0)
		(effects
			(font
				(size 1.27 1.27)
			)
			(justify left bottom)
		)
	)
	(text "FAN connector"
		(exclude_from_sim no)
		(at 284.48 19.05 0)
		(effects
			(font
				(size 2.0066 2.0066)
				(thickness 0.4013)
				(bold yes)
			)
			(justify left bottom)
		)
	)
	(text "UID"
		(exclude_from_sim no)
		(at 212.09 242.57 0)
		(effects
			(font
				(size 2 2)
				(thickness 0.4013)
				(bold yes)
			)
			(justify left bottom)
		)
	)
	(text "ON/OFF Button controller"
		(exclude_from_sim no)
		(at 15.24 125.73 0)
		(effects
			(font
				(size 2 2)
				(thickness 0.4)
				(bold yes)
			)
			(justify left bottom)
		)
	)
	(text "PCIe_PWR"
		(exclude_from_sim no)
		(at 40.64 76.2 0)
		(effects
			(font
				(size 1.27 1.27)
			)
			(justify left bottom)
		)
	)
	(text "NOTE:\n1. AUTO ON/ PB-Controller\n2. 8s off/ instant off\n3. PWR I2C MUX input select 1\n4. PWR I2C MUX input select 2\n5. JTAG/SPI FLASH\n6. USER_IN\n7. Connect QDCDC2 I^{2}C\n8. Disable FTDI JTAG"
		(exclude_from_sim no)
		(at 111.76 279.4 0)
		(effects
			(font
				(size 1.27 1.27)
			)
			(justify left bottom)
		)
	)
	(text "DC_PWR_AUX"
		(exclude_from_sim no)
		(at 33.02 57.15 0)
		(effects
			(font
				(size 1.27 1.27)
			)
			(justify left bottom)
		)
	)
	(text "Ground probe pads"
		(exclude_from_sim no)
		(at 303.53 241.3 0)
		(effects
			(font
				(size 2 2)
				(thickness 0.4)
				(bold yes)
			)
			(justify left bottom)
		)
	)
	(text "Power supply"
		(exclude_from_sim no)
		(at 13.97 20.32 0)
		(effects
			(font
				(size 3 3)
				(thickness 0.6)
				(bold yes)
			)
			(justify left bottom)
		)
	)
	(text "DC-DCs"
		(exclude_from_sim no)
		(at 326.39 127 0)
		(effects
			(font
				(size 2.0066 2.0066)
				(thickness 0.4013)
				(bold yes)
			)
			(justify left bottom)
		)
	)
	(text "Heater connector"
		(exclude_from_sim no)
		(at 283.21 69.215 0)
		(effects
			(font
				(size 2.0066 2.0066)
				(thickness 0.4013)
				(bold yes)
			)
			(justify left bottom)
		)
	)
	(text "Power good"
		(exclude_from_sim no)
		(at 152.4 242.57 0)
		(effects
			(font
				(size 2.0066 2.0066)
				(thickness 0.4013)
				(bold yes)
			)
			(justify left bottom)
		)
	)
	(junction
		(at 229.87 176.53)
		(diameter 0)
		(color 0 0 0 0)
	)
	(junction
		(at 316.23 78.74)
		(diameter 0)
		(color 0 0 0 0)
	)
	(junction
		(at 299.72 185.42)
		(diameter 0)
		(color 0 0 0 0)
	)
	(junction
		(at 309.88 187.96)
		(diameter 0)
		(color 0 0 0 0)
	)
	(junction
		(at 339.09 43.18)
		(diameter 0)
		(color 0 0 0 0)
	)
	(junction
		(at 355.6 160.02)
		(diameter 0)
		(color 0 0 0 0)
	)
	(junction
		(at 278.13 167.64)
		(diameter 0)
		(color 0 0 0 0)
	)
	(junction
		(at 171.45 264.16)
		(diameter 0)
		(color 0 0 0 0)
	)
	(junction
		(at 364.49 83.82)
		(diameter 0)
		(color 0 0 0 0)
	)
	(junction
		(at 72.39 165.1)
		(diameter 0)
		(color 0 0 0 0)
	)
	(junction
		(at 72.39 179.07)
		(diameter 0)
		(color 0 0 0 0)
	)
	(junction
		(at 86.36 44.45)
		(diameter 0)
		(color 0 0 0 0)
	)
	(junction
		(at 226.06 101.6)
		(diameter 0)
		(color 0 0 0 0)
	)
	(junction
		(at 238.76 48.26)
		(diameter 0)
		(color 0 0 0 0)
	)
	(junction
		(at 325.12 97.79)
		(diameter 0)
		(color 0 0 0 0)
	)
	(junction
		(at 179.07 88.9)
		(diameter 0)
		(color 0 0 0 0)
	)
	(junction
		(at 77.47 236.22)
		(diameter 0)
		(color 0 0 0 0)
	)
	(junction
		(at 262.89 167.64)
		(diameter 0)
		(color 0 0 0 0)
	)
	(junction
		(at 290.83 167.64)
		(diameter 0)
		(color 0 0 0 0)
	)
	(junction
		(at 53.34 44.45)
		(diameter 0)
		(color 0 0 0 0)
	)
	(junction
		(at 86.36 64.77)
		(diameter 0)
		(color 0 0 0 0)
	)
	(junction
		(at 171.45 266.7)
		(diameter 0)
		(color 0 0 0 0)
	)
	(junction
		(at 328.93 24.13)
		(diameter 0)
		(color 0 0 0 0)
	)
	(junction
		(at 355.6 186.69)
		(diameter 0)
		(color 0 0 0 0)
	)
	(junction
		(at 86.36 87.63)
		(diameter 0)
		(color 0 0 0 0)
	)
	(junction
		(at 130.81 77.47)
		(diameter 0)
		(color 0 0 0 0)
	)
	(junction
		(at 63.5 231.14)
		(diameter 0)
		(color 0 0 0 0)
	)
	(junction
		(at 49.53 49.53)
		(diameter 0)
		(color 0 0 0 0)
	)
	(junction
		(at 124.46 54.61)
		(diameter 0)
		(color 0 0 0 0)
	)
	(junction
		(at 233.68 96.52)
		(diameter 0)
		(color 0 0 0 0)
	)
	(junction
		(at 86.36 59.69)
		(diameter 0)
		(color 0 0 0 0)
	)
	(junction
		(at 86.36 77.47)
		(diameter 0)
		(color 0 0 0 0)
	)
	(junction
		(at 86.36 54.61)
		(diameter 0)
		(color 0 0 0 0)
	)
	(junction
		(at 135.89 77.47)
		(diameter 0)
		(color 0 0 0 0)
	)
	(junction
		(at 335.28 106.68)
		(diameter 0)
		(color 0 0 0 0)
	)
	(junction
		(at 354.33 157.48)
		(diameter 0)
		(color 0 0 0 0)
	)
	(junction
		(at 85.09 156.21)
		(diameter 0)
		(color 0 0 0 0)
	)
	(junction
		(at 250.19 87.63)
		(diameter 0)
		(color 0 0 0 0)
	)
	(junction
		(at 307.34 78.74)
		(diameter 0)
		(color 0 0 0 0)
	)
	(junction
		(at 92.71 243.84)
		(diameter 0)
		(color 0 0 0 0)
	)
	(junction
		(at 354.33 184.15)
		(diameter 0)
		(color 0 0 0 0)
	)
	(junction
		(at 185.42 88.9)
		(diameter 0)
		(color 0 0 0 0)
	)
	(junction
		(at 290.83 182.88)
		(diameter 0)
		(color 0 0 0 0)
	)
	(junction
		(at 92.71 233.68)
		(diameter 0)
		(color 0 0 0 0)
	)
	(junction
		(at 314.96 40.64)
		(diameter 0)
		(color 0 0 0 0)
	)
	(junction
		(at 199.39 36.83)
		(diameter 0)
		(color 0 0 0 0)
	)
	(junction
		(at 231.14 36.83)
		(diameter 0)
		(color 0 0 0 0)
	)
	(junction
		(at 92.71 241.3)
		(diameter 0)
		(color 0 0 0 0)
	)
	(junction
		(at 257.81 185.42)
		(diameter 0)
		(color 0 0 0 0)
	)
	(junction
		(at 167.64 187.96)
		(diameter 0)
		(color 0 0 0 0)
	)
	(junction
		(at 299.72 167.64)
		(diameter 0)
		(color 0 0 0 0)
	)
	(junction
		(at 92.71 231.14)
		(diameter 0)
		(color 0 0 0 0)
	)
	(junction
		(at 49.53 57.15)
		(diameter 0)
		(color 0 0 0 0)
	)
	(junction
		(at 88.9 134.62)
		(diameter 0)
		(color 0 0 0 0)
	)
	(junction
		(at 171.45 269.24)
		(diameter 0)
		(color 0 0 0 0)
	)
	(junction
		(at 39.37 171.45)
		(diameter 0)
		(color 0 0 0 0)
	)
	(junction
		(at 62.23 77.47)
		(diameter 0)
		(color 0 0 0 0)
	)
	(junction
		(at 130.81 44.45)
		(diameter 0)
		(color 0 0 0 0)
	)
	(junction
		(at 60.96 228.6)
		(diameter 0)
		(color 0 0 0 0)
	)
	(junction
		(at 335.28 87.63)
		(diameter 0)
		(color 0 0 0 0)
	)
	(junction
		(at 53.34 77.47)
		(diameter 0)
		(color 0 0 0 0)
	)
	(junction
		(at 77.47 87.63)
		(diameter 0)
		(color 0 0 0 0)
	)
	(junction
		(at 86.36 97.79)
		(diameter 0)
		(color 0 0 0 0)
	)
	(junction
		(at 77.47 54.61)
		(diameter 0)
		(color 0 0 0 0)
	)
	(junction
		(at 325.12 78.74)
		(diameter 0)
		(color 0 0 0 0)
	)
	(junction
		(at 198.12 167.64)
		(diameter 0)
		(color 0 0 0 0)
	)
	(junction
		(at 130.81 54.61)
		(diameter 0)
		(color 0 0 0 0)
	)
	(junction
		(at 189.23 36.83)
		(diameter 0)
		(color 0 0 0 0)
	)
	(junction
		(at 180.34 177.8)
		(diameter 0)
		(color 0 0 0 0)
	)
	(junction
		(at 69.85 44.45)
		(diameter 0)
		(color 0 0 0 0)
	)
	(junction
		(at 238.76 36.83)
		(diameter 0)
		(color 0 0 0 0)
	)
	(junction
		(at 86.36 92.71)
		(diameter 0)
		(color 0 0 0 0)
	)
	(junction
		(at 49.53 53.34)
		(diameter 0)
		(color 0 0 0 0)
	)
	(junction
		(at 130.81 87.63)
		(diameter 0)
		(color 0 0 0 0)
	)
	(no_connect
		(at 341.63 38.1)
	)
	(no_connect
		(at 105.41 92.71)
	)
	(no_connect
		(at 105.41 59.69)
	)
	(bus_entry
		(at 237.49 264.16)
		(size -2.54 -2.54)
		(stroke
			(width 0)
			(type default)
		)
	)
	(bus_entry
		(at 344.17 157.48)
		(size -2.54 -2.54)
		(stroke
			(width 0)
			(type default)
		)
	)
	(bus_entry
		(at 34.29 238.76)
		(size -2.54 -2.54)
		(stroke
			(width 0)
			(type default)
		)
	)
	(bus_entry
		(at 194.31 99.06)
		(size 2.54 -2.54)
		(stroke
			(width 0)
			(type default)
		)
	)
	(bus_entry
		(at 237.49 261.62)
		(size -2.54 -2.54)
		(stroke
			(width 0)
			(type default)
		)
	)
	(bus_entry
		(at 194.31 101.6)
		(size 2.54 -2.54)
		(stroke
			(width 0)
			(type default)
		)
	)
	(bus_entry
		(at 344.17 160.02)
		(size -2.54 -2.54)
		(stroke
			(width 0)
			(type default)
		)
	)
	(wire
		(pts
			(xy 370.84 95.25) (xy 370.84 97.79)
		)
		(stroke
			(width 0)
			(type default)
		)
	)
	(wire
		(pts
			(xy 181.61 269.24) (xy 187.96 269.24)
		)
		(stroke
			(width 0)
			(type default)
		)
	)
	(wire
		(pts
			(xy 233.68 96.52) (xy 233.68 99.06)
		)
		(stroke
			(width 0)
			(type default)
		)
	)
	(bus
		(pts
			(xy 27.94 233.68) (xy 30.48 233.68)
		)
		(stroke
			(width 0)
			(type default)
		)
	)
	(wire
		(pts
			(xy 314.96 40.64) (xy 341.63 40.64)
		)
		(stroke
			(width 0)
			(type default)
		)
	)
	(wire
		(pts
			(xy 325.12 106.68) (xy 335.28 106.68)
		)
		(stroke
			(width 0)
			(type default)
		)
	)
	(wire
		(pts
			(xy 354.33 184.15) (xy 354.33 208.28)
		)
		(stroke
			(width 0)
			(type default)
		)
	)
	(wire
		(pts
			(xy 49.53 49.53) (xy 43.18 49.53)
		)
		(stroke
			(width 0)
			(type default)
		)
	)
	(wire
		(pts
			(xy 135.89 76.2) (xy 135.89 77.47)
		)
		(stroke
			(width 0)
			(type default)
		)
	)
	(wire
		(pts
			(xy 262.89 175.26) (xy 262.89 176.53)
		)
		(stroke
			(width 0)
			(type default)
		)
	)
	(wire
		(pts
			(xy 49.53 53.34) (xy 53.34 53.34)
		)
		(stroke
			(width 0)
			(type default)
		)
	)
	(wire
		(pts
			(xy 171.45 257.81) (xy 171.45 256.54)
		)
		(stroke
			(width 0)
			(type default)
		)
	)
	(wire
		(pts
			(xy 86.36 59.69) (xy 86.36 64.77)
		)
		(stroke
			(width 0)
			(type default)
		)
	)
	(wire
		(pts
			(xy 72.39 165.1) (xy 72.39 167.64)
		)
		(stroke
			(width 0)
			(type default)
		)
	)
	(wire
		(pts
			(xy 273.05 264.16) (xy 269.24 264.16)
		)
		(stroke
			(width 0)
			(type default)
		)
	)
	(bus
		(pts
			(xy 193.04 105.41) (xy 194.31 104.14)
		)
		(stroke
			(width 0)
			(type default)
		)
	)
	(wire
		(pts
			(xy 105.41 57.15) (xy 115.57 57.15)
		)
		(stroke
			(width 0)
			(type default)
		)
	)
	(wire
		(pts
			(xy 195.58 93.98) (xy 195.58 88.9)
		)
		(stroke
			(width 0)
			(type default)
		)
	)
	(polyline
		(pts
			(xy 407.67 64.135) (xy 281.94 64.135)
		)
		(stroke
			(width 0)
			(type default)
		)
	)
	(wire
		(pts
			(xy 107.95 236.22) (xy 91.44 236.22)
		)
		(stroke
			(width 0)
			(type default)
		)
	)
	(wire
		(pts
			(xy 325.12 100.33) (xy 325.12 97.79)
		)
		(stroke
			(width 0)
			(type default)
		)
	)
	(wire
		(pts
			(xy 336.55 24.13) (xy 336.55 35.56)
		)
		(stroke
			(width 0)
			(type default)
		)
	)
	(wire
		(pts
			(xy 106.68 153.67) (xy 107.95 153.67)
		)
		(stroke
			(width 0)
			(type default)
		)
	)
	(wire
		(pts
			(xy 273.05 261.62) (xy 269.24 261.62)
		)
		(stroke
			(width 0)
			(type default)
		)
	)
	(polyline
		(pts
			(xy 281.94 12.7) (xy 281.94 119.38)
		)
		(stroke
			(width 0)
			(type default)
		)
	)
	(wire
		(pts
			(xy 63.5 215.9) (xy 63.5 214.63)
		)
		(stroke
			(width 0)
			(type default)
		)
	)
	(wire
		(pts
			(xy 189.23 33.02) (xy 189.23 36.83)
		)
		(stroke
			(width 0)
			(type default)
		)
	)
	(wire
		(pts
			(xy 299.72 179.07) (xy 299.72 185.42)
		)
		(stroke
			(width 0)
			(type default)
		)
	)
	(wire
		(pts
			(xy 119.38 153.67) (xy 119.38 156.21)
		)
		(stroke
			(width 0)
			(type default)
		)
	)
	(wire
		(pts
			(xy 180.34 177.8) (xy 180.34 179.07)
		)
		(stroke
			(width 0)
			(type default)
		)
	)
	(wire
		(pts
			(xy 119.38 44.45) (xy 130.81 44.45)
		)
		(stroke
			(width 0)
			(type default)
		)
	)
	(wire
		(pts
			(xy 189.23 36.83) (xy 199.39 36.83)
		)
		(stroke
			(width 0)
			(type default)
		)
	)
	(wire
		(pts
			(xy 63.5 231.14) (xy 78.74 231.14)
		)
		(stroke
			(width 0)
			(type default)
		)
	)
	(wire
		(pts
			(xy 355.6 186.69) (xy 355.6 160.02)
		)
		(stroke
			(width 0)
			(type default)
		)
	)
	(wire
		(pts
			(xy 367.03 243.84) (xy 365.76 243.84)
		)
		(stroke
			(width 0)
			(type default)
		)
	)
	(wire
		(pts
			(xy 49.53 53.34) (xy 49.53 57.15)
		)
		(stroke
			(width 0)
			(type default)
		)
	)
	(wire
		(pts
			(xy 307.34 78.74) (xy 316.23 78.74)
		)
		(stroke
			(width 0)
			(type default)
		)
	)
	(wire
		(pts
			(xy 58.42 231.14) (xy 63.5 231.14)
		)
		(stroke
			(width 0)
			(type default)
		)
	)
	(wire
		(pts
			(xy 60.96 236.22) (xy 77.47 236.22)
		)
		(stroke
			(width 0)
			(type default)
		)
	)
	(wire
		(pts
			(xy 113.03 236.22) (xy 115.57 236.22)
		)
		(stroke
			(width 0)
			(type default)
		)
	)
	(wire
		(pts
			(xy 39.37 170.18) (xy 39.37 171.45)
		)
		(stroke
			(width 0)
			(type default)
		)
	)
	(polyline
		(pts
			(xy 299.72 236.22) (xy 299.72 252.73)
		)
		(stroke
			(width 0)
			(type default)
		)
	)
	(wire
		(pts
			(xy 238.76 53.34) (xy 238.76 48.26)
		)
		(stroke
			(width 0)
			(type default)
		)
	)
	(wire
		(pts
			(xy 91.44 241.3) (xy 92.71 241.3)
		)
		(stroke
			(width 0)
			(type default)
		)
	)
	(wire
		(pts
			(xy 257.81 191.77) (xy 257.81 193.04)
		)
		(stroke
			(width 0)
			(type default)
		)
	)
	(wire
		(pts
			(xy 130.81 95.25) (xy 130.81 101.6)
		)
		(stroke
			(width 0)
			(type default)
		)
	)
	(wire
		(pts
			(xy 335.28 87.63) (xy 335.28 88.9)
		)
		(stroke
			(width 0)
			(type default)
		)
	)
	(wire
		(pts
			(xy 231.14 36.83) (xy 238.76 36.83)
		)
		(stroke
			(width 0)
			(type default)
		)
	)
	(wire
		(pts
			(xy 86.36 44.45) (xy 106.68 44.45)
		)
		(stroke
			(width 0)
			(type default)
		)
	)
	(wire
		(pts
			(xy 77.47 95.25) (xy 77.47 97.79)
		)
		(stroke
			(width 0)
			(type default)
		)
	)
	(wire
		(pts
			(xy 262.89 167.64) (xy 262.89 170.18)
		)
		(stroke
			(width 0)
			(type default)
		)
	)
	(wire
		(pts
			(xy 63.5 241.3) (xy 78.74 241.3)
		)
		(stroke
			(width 0)
			(type default)
		)
	)
	(wire
		(pts
			(xy 325.12 78.74) (xy 325.12 81.28)
		)
		(stroke
			(width 0)
			(type default)
		)
	)
	(wire
		(pts
			(xy 365.76 81.28) (xy 364.49 81.28)
		)
		(stroke
			(width 0)
			(type default)
		)
	)
	(wire
		(pts
			(xy 189.23 46.99) (xy 189.23 52.07)
		)
		(stroke
			(width 0)
			(type default)
		)
	)
	(wire
		(pts
			(xy 224.79 93.98) (xy 227.33 93.98)
		)
		(stroke
			(width 0)
			(type default)
		)
	)
	(wire
		(pts
			(xy 130.81 54.61) (xy 130.81 77.47)
		)
		(stroke
			(width 0)
			(type default)
		)
	)
	(wire
		(pts
			(xy 204.47 195.58) (xy 204.47 191.77)
		)
		(stroke
			(width 0)
			(type default)
		)
	)
	(wire
		(pts
			(xy 135.89 77.47) (xy 142.24 77.47)
		)
		(stroke
			(width 0)
			(type default)
		)
	)
	(wire
		(pts
			(xy 167.64 187.96) (xy 167.64 189.23)
		)
		(stroke
			(width 0)
			(type default)
		)
	)
	(wire
		(pts
			(xy 86.36 44.45) (xy 86.36 54.61)
		)
		(stroke
			(width 0)
			(type default)
		)
	)
	(wire
		(pts
			(xy 290.83 179.07) (xy 290.83 182.88)
		)
		(stroke
			(width 0)
			(type default)
		)
	)
	(wire
		(pts
			(xy 364.49 83.82) (xy 364.49 86.36)
		)
		(stroke
			(width 0)
			(type default)
		)
	)
	(wire
		(pts
			(xy 72.39 158.75) (xy 72.39 165.1)
		)
		(stroke
			(width 0)
			(type default)
		)
	)
	(wire
		(pts
			(xy 93.98 134.62) (xy 93.98 135.89)
		)
		(stroke
			(width 0)
			(type default)
		)
	)
	(wire
		(pts
			(xy 167.64 187.96) (xy 172.72 187.96)
		)
		(stroke
			(width 0)
			(type default)
		)
	)
	(wire
		(pts
			(xy 119.38 146.05) (xy 119.38 148.59)
		)
		(stroke
			(width 0)
			(type default)
		)
	)
	(wire
		(pts
			(xy 179.07 88.9) (xy 179.07 90.17)
		)
		(stroke
			(width 0)
			(type default)
		)
	)
	(wire
		(pts
			(xy 53.34 77.47) (xy 53.34 80.01)
		)
		(stroke
			(width 0)
			(type default)
		)
	)
	(wire
		(pts
			(xy 325.12 105.41) (xy 325.12 106.68)
		)
		(stroke
			(width 0)
			(type default)
		)
	)
	(wire
		(pts
			(xy 194.31 177.8) (xy 180.34 177.8)
		)
		(stroke
			(width 0)
			(type default)
		)
	)
	(wire
		(pts
			(xy 72.39 179.07) (xy 72.39 180.34)
		)
		(stroke
			(width 0)
			(type default)
		)
	)
	(wire
		(pts
			(xy 354.33 208.28) (xy 364.49 208.28)
		)
		(stroke
			(width 0)
			(type default)
		)
	)
	(wire
		(pts
			(xy 229.87 161.29) (xy 229.87 170.18)
		)
		(stroke
			(width 0)
			(type default)
		)
	)
	(wire
		(pts
			(xy 198.12 173.99) (xy 198.12 175.26)
		)
		(stroke
			(width 0)
			(type default)
		)
	)
	(wire
		(pts
			(xy 328.93 24.13) (xy 328.93 26.67)
		)
		(stroke
			(width 0)
			(type default)
		)
	)
	(wire
		(pts
			(xy 309.88 167.64) (xy 309.88 173.99)
		)
		(stroke
			(width 0)
			(type default)
		)
	)
	(wire
		(pts
			(xy 53.34 76.2) (xy 53.34 77.47)
		)
		(stroke
			(width 0)
			(type default)
		)
	)
	(wire
		(pts
			(xy 314.96 33.02) (xy 314.96 34.29)
		)
		(stroke
			(width 0)
			(type default)
		)
	)
	(wire
		(pts
			(xy 179.07 88.9) (xy 185.42 88.9)
		)
		(stroke
			(width 0)
			(type default)
		)
	)
	(wire
		(pts
			(xy 290.83 167.64) (xy 290.83 173.99)
		)
		(stroke
			(width 0)
			(type default)
		)
	)
	(wire
		(pts
			(xy 198.12 166.37) (xy 198.12 167.64)
		)
		(stroke
			(width 0)
			(type default)
		)
	)
	(wire
		(pts
			(xy 241.3 104.14) (xy 241.3 105.41)
		)
		(stroke
			(width 0)
			(type default)
		)
	)
	(wire
		(pts
			(xy 180.34 175.26) (xy 180.34 177.8)
		)
		(stroke
			(width 0)
			(type default)
		)
	)
	(wire
		(pts
			(xy 364.49 213.36) (xy 349.25 213.36)
		)
		(stroke
			(width 0)
			(type default)
		)
	)
	(polyline
		(pts
			(xy 149.86 236.22) (xy 149.86 284.48)
		)
		(stroke
			(width 0)
			(type default)
		)
	)
	(wire
		(pts
			(xy 309.88 187.96) (xy 316.23 187.96)
		)
		(stroke
			(width 0)
			(type default)
		)
	)
	(wire
		(pts
			(xy 43.18 44.45) (xy 53.34 44.45)
		)
		(stroke
			(width 0)
			(type default)
		)
	)
	(wire
		(pts
			(xy 307.34 87.63) (xy 307.34 86.36)
		)
		(stroke
			(width 0)
			(type default)
		)
	)
	(wire
		(pts
			(xy 238.76 45.72) (xy 238.76 48.26)
		)
		(stroke
			(width 0)
			(type default)
		)
	)
	(wire
		(pts
			(xy 335.28 107.95) (xy 335.28 106.68)
		)
		(stroke
			(width 0)
			(type default)
		)
	)
	(wire
		(pts
			(xy 124.46 54.61) (xy 130.81 54.61)
		)
		(stroke
			(width 0)
			(type default)
		)
	)
	(wire
		(pts
			(xy 328.93 31.75) (xy 328.93 33.02)
		)
		(stroke
			(width 0)
			(type default)
		)
	)
	(wire
		(pts
			(xy 43.18 46.99) (xy 49.53 46.99)
		)
		(stroke
			(width 0)
			(type default)
		)
	)
	(wire
		(pts
			(xy 299.72 185.42) (xy 316.23 185.42)
		)
		(stroke
			(width 0)
			(type default)
		)
	)
	(wire
		(pts
			(xy 201.93 167.64) (xy 201.93 186.69)
		)
		(stroke
			(width 0)
			(type default)
		)
	)
	(wire
		(pts
			(xy 92.71 241.3) (xy 92.71 233.68)
		)
		(stroke
			(width 0)
			(type default)
		)
	)
	(wire
		(pts
			(xy 179.07 95.25) (xy 179.07 96.52)
		)
		(stroke
			(width 0)
			(type default)
		)
	)
	(wire
		(pts
			(xy 335.28 87.63) (xy 335.28 86.36)
		)
		(stroke
			(width 0)
			(type default)
		)
	)
	(polyline
		(pts
			(xy 149.86 82.55) (xy 149.86 236.22)
		)
		(stroke
			(width 0)
			(type default)
		)
	)
	(wire
		(pts
			(xy 356.87 78.74) (xy 365.76 78.74)
		)
		(stroke
			(width 0)
			(type default)
		)
	)
	(wire
		(pts
			(xy 86.36 54.61) (xy 87.63 54.61)
		)
		(stroke
			(width 0)
			(type default)
		)
	)
	(wire
		(pts
			(xy 86.36 87.63) (xy 77.47 87.63)
		)
		(stroke
			(width 0)
			(type default)
		)
	)
	(wire
		(pts
			(xy 130.81 77.47) (xy 130.81 87.63)
		)
		(stroke
			(width 0)
			(type default)
		)
	)
	(wire
		(pts
			(xy 171.45 266.7) (xy 171.45 269.24)
		)
		(stroke
			(width 0)
			(type default)
		)
	)
	(wire
		(pts
			(xy 92.71 243.84) (xy 92.71 245.11)
		)
		(stroke
			(width 0)
			(type default)
		)
	)
	(wire
		(pts
			(xy 86.36 59.69) (xy 87.63 59.69)
		)
		(stroke
			(width 0)
			(type default)
		)
	)
	(wire
		(pts
			(xy 262.89 166.37) (xy 262.89 167.64)
		)
		(stroke
			(width 0)
			(type default)
		)
	)
	(polyline
		(pts
			(xy 77.47 278.13) (xy 77.47 278.13)
		)
		(stroke
			(width 0)
			(type default)
		)
	)
	(wire
		(pts
			(xy 176.53 269.24) (xy 171.45 269.24)
		)
		(stroke
			(width 0)
			(type default)
		)
	)
	(wire
		(pts
			(xy 88.9 134.62) (xy 88.9 133.35)
		)
		(stroke
			(width 0)
			(type default)
		)
	)
	(wire
		(pts
			(xy 72.39 158.75) (xy 88.9 158.75)
		)
		(stroke
			(width 0)
			(type default)
		)
	)
	(wire
		(pts
			(xy 325.12 87.63) (xy 335.28 87.63)
		)
		(stroke
			(width 0)
			(type default)
		)
	)
	(wire
		(pts
			(xy 171.45 266.7) (xy 176.53 266.7)
		)
		(stroke
			(width 0)
			(type default)
		)
	)
	(wire
		(pts
			(xy 198.12 167.64) (xy 198.12 168.91)
		)
		(stroke
			(width 0)
			(type default)
		)
	)
	(wire
		(pts
			(xy 69.85 165.1) (xy 69.85 167.64)
		)
		(stroke
			(width 0)
			(type default)
		)
	)
	(wire
		(pts
			(xy 49.53 57.15) (xy 69.85 57.15)
		)
		(stroke
			(width 0)
			(type default)
		)
	)
	(wire
		(pts
			(xy 107.95 146.05) (xy 107.95 153.67)
		)
		(stroke
			(width 0)
			(type default)
		)
	)
	(wire
		(pts
			(xy 86.36 77.47) (xy 106.68 77.47)
		)
		(stroke
			(width 0)
			(type default)
		)
	)
	(wire
		(pts
			(xy 339.09 43.18) (xy 341.63 43.18)
		)
		(stroke
			(width 0)
			(type default)
		)
	)
	(wire
		(pts
			(xy 107.95 146.05) (xy 119.38 146.05)
		)
		(stroke
			(width 0)
			(type default)
		)
	)
	(wire
		(pts
			(xy 77.47 250.19) (xy 77.47 251.46)
		)
		(stroke
			(width 0)
			(type default)
		)
	)
	(wire
		(pts
			(xy 229.87 194.31) (xy 229.87 193.04)
		)
		(stroke
			(width 0)
			(type default)
		)
	)
	(wire
		(pts
			(xy 111.76 158.75) (xy 111.76 161.29)
		)
		(stroke
			(width 0)
			(type default)
		)
	)
	(wire
		(pts
			(xy 228.6 48.26) (xy 228.6 39.37)
		)
		(stroke
			(width 0)
			(type default)
		)
	)
	(wire
		(pts
			(xy 87.63 90.17) (xy 86.36 90.17)
		)
		(stroke
			(width 0)
			(type default)
		)
	)
	(wire
		(pts
			(xy 354.33 184.15) (xy 364.49 184.15)
		)
		(stroke
			(width 0)
			(type default)
		)
	)
	(wire
		(pts
			(xy 69.85 179.07) (xy 72.39 179.07)
		)
		(stroke
			(width 0)
			(type default)
		)
	)
	(wire
		(pts
			(xy 69.85 44.45) (xy 86.36 44.45)
		)
		(stroke
			(width 0)
			(type default)
		)
	)
	(wire
		(pts
			(xy 170.18 269.24) (xy 171.45 269.24)
		)
		(stroke
			(width 0)
			(type default)
		)
	)
	(wire
		(pts
			(xy 105.41 54.61) (xy 124.46 54.61)
		)
		(stroke
			(width 0)
			(type default)
		)
	)
	(wire
		(pts
			(xy 91.44 223.52) (xy 106.68 223.52)
		)
		(stroke
			(width 0)
			(type default)
		)
	)
	(wire
		(pts
			(xy 58.42 228.6) (xy 60.96 228.6)
		)
		(stroke
			(width 0)
			(type default)
		)
	)
	(wire
		(pts
			(xy 85.09 156.21) (xy 88.9 156.21)
		)
		(stroke
			(width 0)
			(type default)
		)
	)
	(wire
		(pts
			(xy 91.44 231.14) (xy 92.71 231.14)
		)
		(stroke
			(width 0)
			(type default)
		)
	)
	(wire
		(pts
			(xy 224.79 99.06) (xy 226.06 99.06)
		)
		(stroke
			(width 0)
			(type default)
		)
	)
	(wire
		(pts
			(xy 354.33 157.48) (xy 354.33 184.15)
		)
		(stroke
			(width 0)
			(type default)
		)
	)
	(wire
		(pts
			(xy 77.47 53.34) (xy 77.47 54.61)
		)
		(stroke
			(width 0)
			(type default)
		)
	)
	(wire
		(pts
			(xy 92.71 228.6) (xy 91.44 228.6)
		)
		(stroke
			(width 0)
			(type default)
		)
	)
	(wire
		(pts
			(xy 299.72 167.64) (xy 299.72 173.99)
		)
		(stroke
			(width 0)
			(type default)
		)
	)
	(polyline
		(pts
			(xy 149.86 236.22) (xy 299.72 236.22)
		)
		(stroke
			(width 0)
			(type default)
		)
	)
	(wire
		(pts
			(xy 228.6 48.26) (xy 238.76 48.26)
		)
		(stroke
			(width 0)
			(type default)
		)
	)
	(wire
		(pts
			(xy 351.79 243.84) (xy 350.52 243.84)
		)
		(stroke
			(width 0)
			(type default)
		)
	)
	(bus
		(pts
			(xy 193.04 105.41) (xy 191.77 105.41)
		)
		(stroke
			(width 0)
			(type default)
		)
	)
	(wire
		(pts
			(xy 66.04 226.06) (xy 78.74 226.06)
		)
		(stroke
			(width 0)
			(type default)
		)
	)
	(wire
		(pts
			(xy 205.74 189.23) (xy 194.31 189.23)
		)
		(stroke
			(width 0)
			(type default)
		)
	)
	(wire
		(pts
			(xy 290.83 167.64) (xy 299.72 167.64)
		)
		(stroke
			(width 0)
			(type default)
		)
	)
	(bus
		(pts
			(xy 194.31 101.6) (xy 194.31 104.14)
		)
		(stroke
			(width 0)
			(type default)
		)
	)
	(bus
		(pts
			(xy 31.75 234.95) (xy 31.75 236.22)
		)
		(stroke
			(width 0)
			(type default)
		)
	)
	(wire
		(pts
			(xy 205.74 93.98) (xy 195.58 93.98)
		)
		(stroke
			(width 0)
			(type default)
		)
	)
	(wire
		(pts
			(xy 52.07 156.21) (xy 85.09 156.21)
		)
		(stroke
			(width 0)
			(type default)
		)
	)
	(wire
		(pts
			(xy 364.49 83.82) (xy 365.76 83.82)
		)
		(stroke
			(width 0)
			(type default)
		)
	)
	(wire
		(pts
			(xy 52.07 162.56) (xy 52.07 156.21)
		)
		(stroke
			(width 0)
			(type default)
		)
	)
	(wire
		(pts
			(xy 72.39 77.47) (xy 86.36 77.47)
		)
		(stroke
			(width 0)
			(type default)
		)
	)
	(wire
		(pts
			(xy 335.28 106.68) (xy 335.28 101.6)
		)
		(stroke
			(width 0)
			(type default)
		)
	)
	(wire
		(pts
			(xy 257.81 185.42) (xy 252.73 185.42)
		)
		(stroke
			(width 0)
			(type default)
		)
	)
	(wire
		(pts
			(xy 227.33 93.98) (xy 227.33 87.63)
		)
		(stroke
			(width 0)
			(type default)
		)
	)
	(wire
		(pts
			(xy 316.23 87.63) (xy 316.23 86.36)
		)
		(stroke
			(width 0)
			(type default)
		)
	)
	(wire
		(pts
			(xy 39.37 171.45) (xy 39.37 172.72)
		)
		(stroke
			(width 0)
			(type default)
		)
	)
	(wire
		(pts
			(xy 91.44 226.06) (xy 106.68 226.06)
		)
		(stroke
			(width 0)
			(type default)
		)
	)
	(wire
		(pts
			(xy 273.05 266.7) (xy 273.05 264.16)
		)
		(stroke
			(width 0)
			(type default)
		)
	)
	(wire
		(pts
			(xy 181.61 264.16) (xy 187.96 264.16)
		)
		(stroke
			(width 0)
			(type default)
		)
	)
	(wire
		(pts
			(xy 356.87 146.05) (xy 364.49 146.05)
		)
		(stroke
			(width 0)
			(type default)
		)
	)
	(wire
		(pts
			(xy 34.29 238.76) (xy 78.74 238.76)
		)
		(stroke
			(width 0)
			(type default)
		)
	)
	(wire
		(pts
			(xy 77.47 97.79) (xy 86.36 97.79)
		)
		(stroke
			(width 0)
			(type default)
		)
	)
	(wire
		(pts
			(xy 278.13 167.64) (xy 290.83 167.64)
		)
		(stroke
			(width 0)
			(type default)
		)
	)
	(wire
		(pts
			(xy 60.96 228.6) (xy 78.74 228.6)
		)
		(stroke
			(width 0)
			(type default)
		)
	)
	(wire
		(pts
			(xy 370.84 104.14) (xy 370.84 102.87)
		)
		(stroke
			(width 0)
			(type default)
		)
	)
	(wire
		(pts
			(xy 328.93 24.13) (xy 336.55 24.13)
		)
		(stroke
			(width 0)
			(type default)
		)
	)
	(wire
		(pts
			(xy 130.81 44.45) (xy 133.35 44.45)
		)
		(stroke
			(width 0)
			(type default)
		)
	)
	(wire
		(pts
			(xy 69.85 179.07) (xy 69.85 177.8)
		)
		(stroke
			(width 0)
			(type default)
		)
	)
	(wire
		(pts
			(xy 85.09 134.62) (xy 85.09 147.32)
		)
		(stroke
			(width 0)
			(type default)
		)
	)
	(wire
		(pts
			(xy 77.47 62.23) (xy 77.47 64.77)
		)
		(stroke
			(width 0)
			(type default)
		)
	)
	(wire
		(pts
			(xy 257.81 185.42) (xy 267.97 185.42)
		)
		(stroke
			(width 0)
			(type default)
		)
	)
	(bus
		(pts
			(xy 341.63 153.67) (xy 341.63 154.94)
		)
		(stroke
			(width 0)
			(type default)
		)
	)
	(wire
		(pts
			(xy 77.47 87.63) (xy 77.47 90.17)
		)
		(stroke
			(width 0)
			(type default)
		)
	)
	(wire
		(pts
			(xy 39.37 180.34) (xy 39.37 177.8)
		)
		(stroke
			(width 0)
			(type default)
		)
	)
	(wire
		(pts
			(xy 105.41 87.63) (xy 130.81 87.63)
		)
		(stroke
			(width 0)
			(type default)
		)
	)
	(wire
		(pts
			(xy 356.87 200.66) (xy 364.49 200.66)
		)
		(stroke
			(width 0)
			(type default)
		)
	)
	(wire
		(pts
			(xy 179.07 86.36) (xy 179.07 88.9)
		)
		(stroke
			(width 0)
			(type default)
		)
	)
	(wire
		(pts
			(xy 314.96 39.37) (xy 314.96 40.64)
		)
		(stroke
			(width 0)
			(type default)
		)
	)
	(wire
		(pts
			(xy 91.44 238.76) (xy 106.68 238.76)
		)
		(stroke
			(width 0)
			(type default)
		)
	)
	(wire
		(pts
			(xy 115.57 57.15) (xy 115.57 52.07)
		)
		(stroke
			(width 0)
			(type default)
		)
	)
	(wire
		(pts
			(xy 336.55 35.56) (xy 341.63 35.56)
		)
		(stroke
			(width 0)
			(type default)
		)
	)
	(bus
		(pts
			(xy 30.48 233.68) (xy 31.75 234.95)
		)
		(stroke
			(width 0)
			(type default)
		)
	)
	(wire
		(pts
			(xy 238.76 36.83) (xy 240.03 36.83)
		)
		(stroke
			(width 0)
			(type default)
		)
	)
	(wire
		(pts
			(xy 53.34 77.47) (xy 62.23 77.47)
		)
		(stroke
			(width 0)
			(type default)
		)
	)
	(wire
		(pts
			(xy 314.96 41.91) (xy 314.96 40.64)
		)
		(stroke
			(width 0)
			(type default)
		)
	)
	(wire
		(pts
			(xy 185.42 95.25) (xy 185.42 96.52)
		)
		(stroke
			(width 0)
			(type default)
		)
	)
	(wire
		(pts
			(xy 359.41 95.25) (xy 370.84 95.25)
		)
		(stroke
			(width 0)
			(type default)
		)
	)
	(wire
		(pts
			(xy 355.6 186.69) (xy 364.49 186.69)
		)
		(stroke
			(width 0)
			(type default)
		)
	)
	(wire
		(pts
			(xy 85.09 156.21) (xy 85.09 152.4)
		)
		(stroke
			(width 0)
			(type default)
		)
	)
	(polyline
		(pts
			(xy 209.55 236.22) (xy 209.55 284.48)
		)
		(stroke
			(width 0)
			(type default)
		)
	)
	(bus
		(pts
			(xy 234.95 259.08) (xy 234.95 261.62)
		)
		(stroke
			(width 0)
			(type default)
		)
	)
	(wire
		(pts
			(xy 233.68 95.25) (xy 233.68 96.52)
		)
		(stroke
			(width 0)
			(type default)
		)
	)
	(wire
		(pts
			(xy 93.98 134.62) (xy 88.9 134.62)
		)
		(stroke
			(width 0)
			(type default)
		)
	)
	(wire
		(pts
			(xy 167.64 196.85) (xy 167.64 194.31)
		)
		(stroke
			(width 0)
			(type default)
		)
	)
	(wire
		(pts
			(xy 119.38 77.47) (xy 130.81 77.47)
		)
		(stroke
			(width 0)
			(type default)
		)
	)
	(wire
		(pts
			(xy 328.93 22.86) (xy 328.93 24.13)
		)
		(stroke
			(width 0)
			(type default)
		)
	)
	(wire
		(pts
			(xy 53.34 44.45) (xy 59.69 44.45)
		)
		(stroke
			(width 0)
			(type default)
		)
	)
	(wire
		(pts
			(xy 220.98 189.23) (xy 222.25 189.23)
		)
		(stroke
			(width 0)
			(type default)
		)
	)
	(polyline
		(pts
			(xy 281.94 64.135) (xy 149.86 64.135)
		)
		(stroke
			(width 0)
			(type default)
		)
	)
	(wire
		(pts
			(xy 288.29 187.96) (xy 309.88 187.96)
		)
		(stroke
			(width 0)
			(type default)
		)
	)
	(polyline
		(pts
			(xy 323.85 119.38) (xy 323.85 236.22)
		)
		(stroke
			(width 0)
			(type default)
		)
	)
	(wire
		(pts
			(xy 325.12 97.79) (xy 327.66 97.79)
		)
		(stroke
			(width 0)
			(type default)
		)
	)
	(wire
		(pts
			(xy 231.14 35.56) (xy 231.14 36.83)
		)
		(stroke
			(width 0)
			(type default)
		)
	)
	(wire
		(pts
			(xy 87.63 57.15) (xy 86.36 57.15)
		)
		(stroke
			(width 0)
			(type default)
		)
	)
	(wire
		(pts
			(xy 200.66 36.83) (xy 199.39 36.83)
		)
		(stroke
			(width 0)
			(type default)
		)
	)
	(wire
		(pts
			(xy 86.36 77.47) (xy 86.36 87.63)
		)
		(stroke
			(width 0)
			(type default)
		)
	)
	(wire
		(pts
			(xy 66.04 223.52) (xy 78.74 223.52)
		)
		(stroke
			(width 0)
			(type default)
		)
	)
	(wire
		(pts
			(xy 344.17 160.02) (xy 355.6 160.02)
		)
		(stroke
			(width 0)
			(type default)
		)
	)
	(bus
		(pts
			(xy 339.09 153.67) (xy 341.63 153.67)
		)
		(stroke
			(width 0)
			(type default)
		)
	)
	(wire
		(pts
			(xy 39.37 171.45) (xy 44.45 171.45)
		)
		(stroke
			(width 0)
			(type default)
		)
	)
	(wire
		(pts
			(xy 237.49 264.16) (xy 248.92 264.16)
		)
		(stroke
			(width 0)
			(type default)
		)
	)
	(wire
		(pts
			(xy 72.39 179.07) (xy 72.39 177.8)
		)
		(stroke
			(width 0)
			(type default)
		)
	)
	(wire
		(pts
			(xy 77.47 54.61) (xy 77.47 57.15)
		)
		(stroke
			(width 0)
			(type default)
		)
	)
	(wire
		(pts
			(xy 226.06 101.6) (xy 226.06 105.41)
		)
		(stroke
			(width 0)
			(type default)
		)
	)
	(wire
		(pts
			(xy 106.68 158.75) (xy 111.76 158.75)
		)
		(stroke
			(width 0)
			(type default)
		)
	)
	(wire
		(pts
			(xy 52.07 180.34) (xy 52.07 175.26)
		)
		(stroke
			(width 0)
			(type default)
		)
	)
	(wire
		(pts
			(xy 53.34 85.09) (xy 53.34 101.6)
		)
		(stroke
			(width 0)
			(type default)
		)
	)
	(wire
		(pts
			(xy 49.53 57.15) (xy 49.53 58.42)
		)
		(stroke
			(width 0)
			(type default)
		)
	)
	(wire
		(pts
			(xy 60.96 215.9) (xy 60.96 214.63)
		)
		(stroke
			(width 0)
			(type default)
		)
	)
	(wire
		(pts
			(xy 307.34 78.74) (xy 307.34 81.28)
		)
		(stroke
			(width 0)
			(type default)
		)
	)
	(polyline
		(pts
			(xy 149.86 12.7) (xy 149.86 82.55)
		)
		(stroke
			(width 0)
			(type default)
		)
	)
	(wire
		(pts
			(xy 62.23 76.2) (xy 62.23 77.47)
		)
		(stroke
			(width 0)
			(type default)
		)
	)
	(wire
		(pts
			(xy 224.79 96.52) (xy 233.68 96.52)
		)
		(stroke
			(width 0)
			(type default)
		)
	)
	(wire
		(pts
			(xy 201.93 186.69) (xy 205.74 186.69)
		)
		(stroke
			(width 0)
			(type default)
		)
	)
	(wire
		(pts
			(xy 273.05 260.35) (xy 273.05 261.62)
		)
		(stroke
			(width 0)
			(type default)
		)
	)
	(wire
		(pts
			(xy 77.47 86.36) (xy 77.47 87.63)
		)
		(stroke
			(width 0)
			(type default)
		)
	)
	(wire
		(pts
			(xy 200.66 39.37) (xy 199.39 39.37)
		)
		(stroke
			(width 0)
			(type default)
		)
	)
	(wire
		(pts
			(xy 359.41 104.14) (xy 359.41 102.87)
		)
		(stroke
			(width 0)
			(type default)
		)
	)
	(wire
		(pts
			(xy 180.34 196.85) (xy 180.34 191.77)
		)
		(stroke
			(width 0)
			(type default)
		)
	)
	(wire
		(pts
			(xy 284.48 260.35) (xy 284.48 261.62)
		)
		(stroke
			(width 0)
			(type default)
		)
	)
	(bus
		(pts
			(xy 194.31 99.06) (xy 194.31 101.6)
		)
		(stroke
			(width 0)
			(type default)
		)
	)
	(wire
		(pts
			(xy 278.13 167.64) (xy 278.13 177.8)
		)
		(stroke
			(width 0)
			(type default)
		)
	)
	(wire
		(pts
			(xy 199.39 39.37) (xy 199.39 36.83)
		)
		(stroke
			(width 0)
			(type default)
		)
	)
	(wire
		(pts
			(xy 304.8 76.2) (xy 304.8 78.74)
		)
		(stroke
			(width 0)
			(type default)
		)
	)
	(wire
		(pts
			(xy 278.13 194.31) (xy 278.13 193.04)
		)
		(stroke
			(width 0)
			(type default)
		)
	)
	(wire
		(pts
			(xy 91.44 243.84) (xy 92.71 243.84)
		)
		(stroke
			(width 0)
			(type default)
		)
	)
	(wire
		(pts
			(xy 237.49 261.62) (xy 248.92 261.62)
		)
		(stroke
			(width 0)
			(type default)
		)
	)
	(wire
		(pts
			(xy 49.53 46.99) (xy 49.53 49.53)
		)
		(stroke
			(width 0)
			(type default)
		)
	)
	(wire
		(pts
			(xy 252.73 176.53) (xy 252.73 185.42)
		)
		(stroke
			(width 0)
			(type default)
		)
	)
	(wire
		(pts
			(xy 106.68 156.21) (xy 119.38 156.21)
		)
		(stroke
			(width 0)
			(type default)
		)
	)
	(wire
		(pts
			(xy 365.76 243.84) (xy 365.76 245.11)
		)
		(stroke
			(width 0)
			(type default)
		)
	)
	(wire
		(pts
			(xy 105.41 90.17) (xy 115.57 90.17)
		)
		(stroke
			(width 0)
			(type default)
		)
	)
	(wire
		(pts
			(xy 60.96 233.68) (xy 78.74 233.68)
		)
		(stroke
			(width 0)
			(type default)
		)
	)
	(wire
		(pts
			(xy 130.81 87.63) (xy 130.81 90.17)
		)
		(stroke
			(width 0)
			(type default)
		)
	)
	(wire
		(pts
			(xy 227.33 87.63) (xy 250.19 87.63)
		)
		(stroke
			(width 0)
			(type default)
		)
	)
	(wire
		(pts
			(xy 130.81 44.45) (xy 130.81 54.61)
		)
		(stroke
			(width 0)
			(type default)
		)
	)
	(wire
		(pts
			(xy 314.96 54.61) (xy 314.96 57.15)
		)
		(stroke
			(width 0)
			(type default)
		)
	)
	(wire
		(pts
			(xy 290.83 182.88) (xy 316.23 182.88)
		)
		(stroke
			(width 0)
			(type default)
		)
	)
	(bus
		(pts
			(xy 341.63 154.94) (xy 341.63 157.48)
		)
		(stroke
			(width 0)
			(type default)
		)
	)
	(wire
		(pts
			(xy 64.77 44.45) (xy 69.85 44.45)
		)
		(stroke
			(width 0)
			(type default)
		)
	)
	(wire
		(pts
			(xy 250.19 87.63) (xy 250.19 88.9)
		)
		(stroke
			(width 0)
			(type default)
		)
	)
	(wire
		(pts
			(xy 339.09 33.02) (xy 339.09 43.18)
		)
		(stroke
			(width 0)
			(type default)
		)
	)
	(wire
		(pts
			(xy 204.47 191.77) (xy 205.74 191.77)
		)
		(stroke
			(width 0)
			(type default)
		)
	)
	(wire
		(pts
			(xy 344.17 157.48) (xy 354.33 157.48)
		)
		(stroke
			(width 0)
			(type default)
		)
	)
	(wire
		(pts
			(xy 69.85 44.45) (xy 69.85 49.53)
		)
		(stroke
			(width 0)
			(type default)
		)
	)
	(wire
		(pts
			(xy 171.45 264.16) (xy 171.45 262.89)
		)
		(stroke
			(width 0)
			(type default)
		)
	)
	(wire
		(pts
			(xy 167.64 186.69) (xy 167.64 187.96)
		)
		(stroke
			(width 0)
			(type default)
		)
	)
	(wire
		(pts
			(xy 86.36 92.71) (xy 87.63 92.71)
		)
		(stroke
			(width 0)
			(type default)
		)
	)
	(wire
		(pts
			(xy 86.36 57.15) (xy 86.36 59.69)
		)
		(stroke
			(width 0)
			(type default)
		)
	)
	(bus
		(pts
			(xy 233.68 257.81) (xy 234.95 259.08)
		)
		(stroke
			(width 0)
			(type default)
		)
	)
	(wire
		(pts
			(xy 181.61 266.7) (xy 187.96 266.7)
		)
		(stroke
			(width 0)
			(type default)
		)
	)
	(wire
		(pts
			(xy 92.71 231.14) (xy 92.71 228.6)
		)
		(stroke
			(width 0)
			(type default)
		)
	)
	(wire
		(pts
			(xy 171.45 264.16) (xy 176.53 264.16)
		)
		(stroke
			(width 0)
			(type default)
		)
	)
	(wire
		(pts
			(xy 303.53 50.8) (xy 307.34 50.8)
		)
		(stroke
			(width 0)
			(type default)
		)
	)
	(wire
		(pts
			(xy 229.87 175.26) (xy 229.87 176.53)
		)
		(stroke
			(width 0)
			(type default)
		)
	)
	(wire
		(pts
			(xy 185.42 88.9) (xy 195.58 88.9)
		)
		(stroke
			(width 0)
			(type default)
		)
	)
	(wire
		(pts
			(xy 180.34 166.37) (xy 180.34 170.18)
		)
		(stroke
			(width 0)
			(type default)
		)
	)
	(wire
		(pts
			(xy 86.36 97.79) (xy 86.36 101.6)
		)
		(stroke
			(width 0)
			(type default)
		)
	)
	(wire
		(pts
			(xy 364.49 81.28) (xy 364.49 83.82)
		)
		(stroke
			(width 0)
			(type default)
		)
	)
	(wire
		(pts
			(xy 115.57 231.14) (xy 115.57 236.22)
		)
		(stroke
			(width 0)
			(type default)
		)
	)
	(wire
		(pts
			(xy 124.46 54.61) (xy 124.46 57.15)
		)
		(stroke
			(width 0)
			(type default)
		)
	)
	(polyline
		(pts
			(xy 12.7 119.38) (xy 407.67 119.38)
		)
		(stroke
			(width 0)
			(type default)
		)
	)
	(wire
		(pts
			(xy 325.12 86.36) (xy 325.12 87.63)
		)
		(stroke
			(width 0)
			(type default)
		)
	)
	(wire
		(pts
			(xy 194.31 177.8) (xy 194.31 189.23)
		)
		(stroke
			(width 0)
			(type default)
		)
	)
	(polyline
		(pts
			(xy 12.7 193.04) (xy 149.86 193.04)
		)
		(stroke
			(width 0)
			(type default)
		)
	)
	(wire
		(pts
			(xy 86.36 64.77) (xy 86.36 66.04)
		)
		(stroke
			(width 0)
			(type default)
		)
	)
	(wire
		(pts
			(xy 62.23 77.47) (xy 67.31 77.47)
		)
		(stroke
			(width 0)
			(type default)
		)
	)
	(wire
		(pts
			(xy 341.63 33.02) (xy 339.09 33.02)
		)
		(stroke
			(width 0)
			(type default)
		)
	)
	(wire
		(pts
			(xy 247.65 266.7) (xy 248.92 266.7)
		)
		(stroke
			(width 0)
			(type default)
		)
	)
	(wire
		(pts
			(xy 93.98 140.97) (xy 93.98 142.24)
		)
		(stroke
			(width 0)
			(type default)
		)
	)
	(wire
		(pts
			(xy 250.19 87.63) (xy 252.73 87.63)
		)
		(stroke
			(width 0)
			(type default)
		)
	)
	(wire
		(pts
			(xy 53.34 44.45) (xy 53.34 46.99)
		)
		(stroke
			(width 0)
			(type default)
		)
	)
	(wire
		(pts
			(xy 364.49 210.82) (xy 355.6 210.82)
		)
		(stroke
			(width 0)
			(type default)
		)
	)
	(wire
		(pts
			(xy 354.33 157.48) (xy 364.49 157.48)
		)
		(stroke
			(width 0)
			(type default)
		)
	)
	(wire
		(pts
			(xy 228.6 39.37) (xy 220.98 39.37)
		)
		(stroke
			(width 0)
			(type default)
		)
	)
	(wire
		(pts
			(xy 233.68 104.14) (xy 233.68 105.41)
		)
		(stroke
			(width 0)
			(type default)
		)
	)
	(wire
		(pts
			(xy 189.23 36.83) (xy 189.23 41.91)
		)
		(stroke
			(width 0)
			(type default)
		)
	)
	(wire
		(pts
			(xy 250.19 93.98) (xy 250.19 95.25)
		)
		(stroke
			(width 0)
			(type default)
		)
	)
	(wire
		(pts
			(xy 224.79 101.6) (xy 226.06 101.6)
		)
		(stroke
			(width 0)
			(type default)
		)
	)
	(wire
		(pts
			(xy 124.46 62.23) (xy 124.46 66.04)
		)
		(stroke
			(width 0)
			(type default)
		)
	)
	(wire
		(pts
			(xy 288.29 182.88) (xy 290.83 182.88)
		)
		(stroke
			(width 0)
			(type default)
		)
	)
	(wire
		(pts
			(xy 196.85 99.06) (xy 205.74 99.06)
		)
		(stroke
			(width 0)
			(type default)
		)
	)
	(wire
		(pts
			(xy 355.6 160.02) (xy 364.49 160.02)
		)
		(stroke
			(width 0)
			(type default)
		)
	)
	(wire
		(pts
			(xy 130.81 77.47) (xy 135.89 77.47)
		)
		(stroke
			(width 0)
			(type default)
		)
	)
	(wire
		(pts
			(xy 323.85 97.79) (xy 325.12 97.79)
		)
		(stroke
			(width 0)
			(type default)
		)
	)
	(wire
		(pts
			(xy 241.3 96.52) (xy 241.3 99.06)
		)
		(stroke
			(width 0)
			(type default)
		)
	)
	(wire
		(pts
			(xy 288.29 185.42) (xy 299.72 185.42)
		)
		(stroke
			(width 0)
			(type default)
		)
	)
	(wire
		(pts
			(xy 92.71 233.68) (xy 92.71 231.14)
		)
		(stroke
			(width 0)
			(type default)
		)
	)
	(wire
		(pts
			(xy 316.23 78.74) (xy 316.23 81.28)
		)
		(stroke
			(width 0)
			(type default)
		)
	)
	(wire
		(pts
			(xy 262.89 167.64) (xy 278.13 167.64)
		)
		(stroke
			(width 0)
			(type default)
		)
	)
	(wire
		(pts
			(xy 86.36 90.17) (xy 86.36 92.71)
		)
		(stroke
			(width 0)
			(type default)
		)
	)
	(wire
		(pts
			(xy 53.34 52.07) (xy 53.34 53.34)
		)
		(stroke
			(width 0)
			(type default)
		)
	)
	(wire
		(pts
			(xy 91.44 233.68) (xy 92.71 233.68)
		)
		(stroke
			(width 0)
			(type default)
		)
	)
	(wire
		(pts
			(xy 229.87 176.53) (xy 229.87 180.34)
		)
		(stroke
			(width 0)
			(type default)
		)
	)
	(wire
		(pts
			(xy 247.65 269.24) (xy 247.65 266.7)
		)
		(stroke
			(width 0)
			(type default)
		)
	)
	(wire
		(pts
			(xy 171.45 264.16) (xy 171.45 266.7)
		)
		(stroke
			(width 0)
			(type default)
		)
	)
	(wire
		(pts
			(xy 226.06 99.06) (xy 226.06 101.6)
		)
		(stroke
			(width 0)
			(type default)
		)
	)
	(wire
		(pts
			(xy 325.12 78.74) (xy 331.47 78.74)
		)
		(stroke
			(width 0)
			(type default)
		)
	)
	(wire
		(pts
			(xy 220.98 36.83) (xy 231.14 36.83)
		)
		(stroke
			(width 0)
			(type default)
		)
	)
	(wire
		(pts
			(xy 86.36 54.61) (xy 77.47 54.61)
		)
		(stroke
			(width 0)
			(type default)
		)
	)
	(wire
		(pts
			(xy 238.76 36.83) (xy 238.76 40.64)
		)
		(stroke
			(width 0)
			(type default)
		)
	)
	(wire
		(pts
			(xy 299.72 167.64) (xy 309.88 167.64)
		)
		(stroke
			(width 0)
			(type default)
		)
	)
	(wire
		(pts
			(xy 88.9 134.62) (xy 88.9 153.67)
		)
		(stroke
			(width 0)
			(type default)
		)
	)
	(wire
		(pts
			(xy 229.87 176.53) (xy 252.73 176.53)
		)
		(stroke
			(width 0)
			(type default)
		)
	)
	(wire
		(pts
			(xy 69.85 54.61) (xy 69.85 57.15)
		)
		(stroke
			(width 0)
			(type default)
		)
	)
	(wire
		(pts
			(xy 198.12 167.64) (xy 201.93 167.64)
		)
		(stroke
			(width 0)
			(type default)
		)
	)
	(wire
		(pts
			(xy 339.09 43.18) (xy 339.09 45.72)
		)
		(stroke
			(width 0)
			(type default)
		)
	)
	(wire
		(pts
			(xy 359.41 95.25) (xy 359.41 97.79)
		)
		(stroke
			(width 0)
			(type default)
		)
	)
	(wire
		(pts
			(xy 115.57 90.17) (xy 115.57 85.09)
		)
		(stroke
			(width 0)
			(type default)
		)
	)
	(wire
		(pts
			(xy 196.85 96.52) (xy 205.74 96.52)
		)
		(stroke
			(width 0)
			(type default)
		)
	)
	(wire
		(pts
			(xy 356.87 173.99) (xy 364.49 173.99)
		)
		(stroke
			(width 0)
			(type default)
		)
	)
	(wire
		(pts
			(xy 238.76 33.02) (xy 238.76 36.83)
		)
		(stroke
			(width 0)
			(type default)
		)
	)
	(wire
		(pts
			(xy 63.5 220.98) (xy 63.5 231.14)
		)
		(stroke
			(width 0)
			(type default)
		)
	)
	(wire
		(pts
			(xy 344.17 78.74) (xy 351.79 78.74)
		)
		(stroke
			(width 0)
			(type default)
		)
	)
	(wire
		(pts
			(xy 257.81 185.42) (xy 257.81 186.69)
		)
		(stroke
			(width 0)
			(type default)
		)
	)
	(wire
		(pts
			(xy 304.8 78.74) (xy 307.34 78.74)
		)
		(stroke
			(width 0)
			(type default)
		)
	)
	(wire
		(pts
			(xy 86.36 92.71) (xy 86.36 97.79)
		)
		(stroke
			(width 0)
			(type default)
		)
	)
	(wire
		(pts
			(xy 92.71 241.3) (xy 92.71 243.84)
		)
		(stroke
			(width 0)
			(type default)
		)
	)
	(wire
		(pts
			(xy 142.24 71.12) (xy 142.24 77.47)
		)
		(stroke
			(width 0)
			(type default)
		)
	)
	(wire
		(pts
			(xy 77.47 236.22) (xy 78.74 236.22)
		)
		(stroke
			(width 0)
			(type default)
		)
	)
	(wire
		(pts
			(xy 49.53 49.53) (xy 49.53 53.34)
		)
		(stroke
			(width 0)
			(type default)
		)
	)
	(polyline
		(pts
			(xy 299.72 236.22) (xy 407.67 236.22)
		)
		(stroke
			(width 0)
			(type default)
		)
	)
	(wire
		(pts
			(xy 69.85 165.1) (xy 72.39 165.1)
		)
		(stroke
			(width 0)
			(type default)
		)
	)
	(wire
		(pts
			(xy 350.52 243.84) (xy 350.52 245.11)
		)
		(stroke
			(width 0)
			(type default)
		)
	)
	(wire
		(pts
			(xy 133.35 44.45) (xy 133.35 41.91)
		)
		(stroke
			(width 0)
			(type default)
		)
	)
	(wire
		(pts
			(xy 86.36 87.63) (xy 87.63 87.63)
		)
		(stroke
			(width 0)
			(type default)
		)
	)
	(wire
		(pts
			(xy 185.42 88.9) (xy 185.42 90.17)
		)
		(stroke
			(width 0)
			(type default)
		)
	)
	(bus
		(pts
			(xy 232.41 257.81) (xy 233.68 257.81)
		)
		(stroke
			(width 0)
			(type default)
		)
	)
	(wire
		(pts
			(xy 77.47 64.77) (xy 86.36 64.77)
		)
		(stroke
			(width 0)
			(type default)
		)
	)
	(wire
		(pts
			(xy 316.23 78.74) (xy 325.12 78.74)
		)
		(stroke
			(width 0)
			(type default)
		)
	)
	(wire
		(pts
			(xy 77.47 236.22) (xy 77.47 245.11)
		)
		(stroke
			(width 0)
			(type default)
		)
	)
	(wire
		(pts
			(xy 355.6 186.69) (xy 355.6 210.82)
		)
		(stroke
			(width 0)
			(type default)
		)
	)
	(wire
		(pts
			(xy 60.96 220.98) (xy 60.96 228.6)
		)
		(stroke
			(width 0)
			(type default)
		)
	)
	(wire
		(pts
			(xy 309.88 179.07) (xy 309.88 187.96)
		)
		(stroke
			(width 0)
			(type default)
		)
	)
	(wire
		(pts
			(xy 233.68 96.52) (xy 241.3 96.52)
		)
		(stroke
			(width 0)
			(type default)
		)
	)
	(label "~{PB_CTRL_IN}"
		(at 72.39 158.75 0)
		(effects
			(font
				(size 1.27 1.27)
			)
			(justify left bottom)
		)
	)
	(label "SEQ_EN"
		(at 229.87 161.29 270)
		(effects
			(font
				(size 1.27 1.27)
			)
			(justify right bottom)
		)
	)
	(label "PWR.SDA"
		(at 237.49 261.62 0)
		(effects
			(font
				(size 1.27 1.27)
			)
			(justify left bottom)
		)
	)
	(label "PWR.SCL"
		(at 237.49 264.16 0)
		(effects
			(font
				(size 1.27 1.27)
			)
			(justify left bottom)
		)
	)
	(label "EN2"
		(at 356.87 173.99 0)
		(effects
			(font
				(size 1.27 1.27)
			)
			(justify left bottom)
		)
	)
	(label "~{PB_CTRL_CLR}"
		(at 106.68 226.06 180)
		(effects
			(font
				(size 1.27 1.27)
			)
			(justify right bottom)
		)
	)
	(label "PWR.SCL"
		(at 344.17 160.02 0)
		(effects
			(font
				(size 1.27 1.27)
			)
			(justify left bottom)
		)
	)
	(label "PWR.SCL"
		(at 34.29 238.76 0)
		(effects
			(font
				(size 1.27 1.27)
			)
			(justify left bottom)
		)
	)
	(label "12V_PCIE_fused"
		(at 80.01 77.47 0)
		(effects
			(font
				(size 1.27 1.27)
			)
			(justify left bottom)
		)
	)
	(label "EN3"
		(at 356.87 200.66 0)
		(effects
			(font
				(size 1.27 1.27)
			)
			(justify left bottom)
		)
	)
	(label "~{PB_CTRL_INT}"
		(at 66.04 226.06 0)
		(effects
			(font
				(size 1.27 1.27)
			)
			(justify left bottom)
		)
	)
	(label "~{PB_CTRL_CLR}"
		(at 72.39 156.21 0)
		(effects
			(font
				(size 1.27 1.27)
			)
			(justify left bottom)
		)
	)
	(label "heater"
		(at 360.68 95.25 0)
		(effects
			(font
				(size 1.27 1.27)
			)
			(justify left bottom)
		)
	)
	(label "heater"
		(at 359.41 78.74 0)
		(effects
			(font
				(size 1.27 1.27)
			)
			(justify left bottom)
		)
	)
	(label "PB_CTRL_OUT"
		(at 85.09 134.62 270)
		(effects
			(font
				(size 1.27 1.27)
			)
			(justify right bottom)
		)
	)
	(label "PB_CTRL_OUT"
		(at 107.95 146.05 0)
		(effects
			(font
				(size 1.27 1.27)
			)
			(justify left bottom)
		)
	)
	(label "PB_CTRL_OUT"
		(at 66.04 223.52 0)
		(effects
			(font
				(size 1.27 1.27)
			)
			(justify left bottom)
		)
	)
	(label "~{PB_CTRL_INT}"
		(at 106.68 156.21 0)
		(effects
			(font
				(size 1.27 1.27)
			)
			(justify left bottom)
		)
	)
	(label "12V_aux_fused"
		(at 69.85 44.45 0)
		(effects
			(font
				(size 1.27 1.27)
			)
			(justify left bottom)
		)
	)
	(label "QDCDC2_SCL"
		(at 349.25 213.36 0)
		(effects
			(font
				(size 1.27 1.27)
			)
			(justify left bottom)
		)
	)
	(label "QDCDC2_SCL"
		(at 106.68 238.76 180)
		(effects
			(font
				(size 1.27 1.27)
			)
			(justify right bottom)
		)
	)
	(label "PWR.SDA"
		(at 344.17 157.48 0)
		(effects
			(font
				(size 1.27 1.27)
			)
			(justify left bottom)
		)
	)
	(label "12V_aux"
		(at 44.45 44.45 0)
		(effects
			(font
				(size 1.27 1.27)
			)
			(justify left bottom)
		)
	)
	(label "PWR.SDA"
		(at 204.47 99.06 180)
		(effects
			(font
				(size 1.27 1.27)
			)
			(justify right bottom)
		)
	)
	(label "SEQ_EN"
		(at 106.68 223.52 180)
		(effects
			(font
				(size 1.27 1.27)
			)
			(justify right bottom)
		)
	)
	(label "EN3"
		(at 316.23 187.96 180)
		(effects
			(font
				(size 1.27 1.27)
			)
			(justify right bottom)
		)
	)
	(label "EN2"
		(at 316.23 185.42 180)
		(effects
			(font
				(size 1.27 1.27)
			)
			(justify right bottom)
		)
	)
	(label "EN1"
		(at 316.23 182.88 180)
		(effects
			(font
				(size 1.27 1.27)
			)
			(justify right bottom)
		)
	)
	(label "EN1"
		(at 356.87 146.05 0)
		(effects
			(font
				(size 1.27 1.27)
			)
			(justify left bottom)
		)
	)
	(label "PWR.SCL"
		(at 204.47 96.52 180)
		(effects
			(font
				(size 1.27 1.27)
			)
			(justify right bottom)
		)
	)
	(global_label "PG1"
		(shape input)
		(at 187.96 264.16 0)
		(fields_autoplaced yes)
		(effects
			(font
				(size 1.27 1.27)
			)
			(justify left)
		)
		(property "Intersheetrefs" "${INTERSHEET_REFS}"
			(at 194.6947 264.16 0)
			(effects
				(font
					(size 1.27 1.27)
				)
				(justify left)
			)
		)
	)
	(global_label "Heater_PWM"
		(shape input)
		(at 323.85 97.79 180)
		(fields_autoplaced yes)
		(effects
			(font
				(size 1.27 1.27)
			)
			(justify right)
		)
		(property "Intersheetrefs" "${INTERSHEET_REFS}"
			(at 310.21 97.79 0)
			(effects
				(font
					(size 1.27 1.27)
				)
				(justify right)
			)
		)
	)
	(global_label "PG2"
		(shape input)
		(at 187.96 266.7 0)
		(fields_autoplaced yes)
		(effects
			(font
				(size 1.27 1.27)
			)
			(justify left)
		)
		(property "Intersheetrefs" "${INTERSHEET_REFS}"
			(at 194.6947 266.7 0)
			(effects
				(font
					(size 1.27 1.27)
				)
				(justify left)
			)
		)
	)
	(global_label "FAN_PWM"
		(shape input)
		(at 303.53 50.8 180)
		(fields_autoplaced yes)
		(effects
			(font
				(size 1.27 1.27)
			)
			(justify right)
		)
		(property "Intersheetrefs" "${INTERSHEET_REFS}"
			(at 292.5577 50.7206 0)
			(effects
				(font
					(size 1.27 1.27)
				)
				(justify right)
			)
		)
	)
	(global_label "FPGA_POWER_CYCLE"
		(shape input)
		(at 167.64 186.69 90)
		(fields_autoplaced yes)
		(effects
			(font
				(size 1.27 1.27)
			)
			(justify left)
		)
		(property "Intersheetrefs" "${INTERSHEET_REFS}"
			(at 167.7194 165.4368 90)
			(effects
				(font
					(size 1.27 1.27)
				)
				(justify left)
			)
		)
	)
	(global_label "MODE2"
		(shape input)
		(at 60.96 233.68 180)
		(fields_autoplaced yes)
		(effects
			(font
				(size 1.27 1.27)
			)
			(justify right)
		)
		(property "Intersheetrefs" "${INTERSHEET_REFS}"
			(at 52.2186 233.68 0)
			(effects
				(font
					(size 1.27 1.27)
				)
				(justify right)
			)
		)
	)
	(global_label "FPGA_POWER_OFF"
		(shape input)
		(at 39.37 170.18 90)
		(fields_autoplaced yes)
		(effects
			(font
				(size 1.27 1.27)
			)
			(justify left)
		)
		(property "Intersheetrefs" "${INTERSHEET_REFS}"
			(at 39.4494 151.2248 90)
			(effects
				(font
					(size 1.27 1.27)
				)
				(justify left)
			)
		)
	)
	(global_label "FTDI_DIS"
		(shape input)
		(at 63.5 241.3 180)
		(fields_autoplaced yes)
		(effects
			(font
				(size 1.27 1.27)
			)
			(justify right)
		)
		(property "Intersheetrefs" "${INTERSHEET_REFS}"
			(at 53.104 241.2206 0)
			(effects
				(font
					(size 1.27 1.27)
				)
				(justify right)
			)
		)
	)
	(global_label "DAC_VREF"
		(shape output)
		(at 252.73 87.63 0)
		(fields_autoplaced yes)
		(effects
			(font
				(size 1.27 1.27)
			)
			(justify left)
		)
		(property "Intersheetrefs" "${INTERSHEET_REFS}"
			(at 264.2466 87.5506 0)
			(effects
				(font
					(size 1.27 1.27)
				)
				(justify left)
			)
		)
	)
	(global_label "PG3"
		(shape input)
		(at 187.96 269.24 0)
		(fields_autoplaced yes)
		(effects
			(font
				(size 1.27 1.27)
			)
			(justify left)
		)
		(property "Intersheetrefs" "${INTERSHEET_REFS}"
			(at 194.6947 269.24 0)
			(effects
				(font
					(size 1.27 1.27)
				)
				(justify left)
			)
		)
	)
	(global_label "POWER"
		(shape input)
		(at 170.18 269.24 180)
		(fields_autoplaced yes)
		(effects
			(font
				(size 1.27 1.27)
			)
			(justify right)
		)
		(property "Intersheetrefs" "${INTERSHEET_REFS}"
			(at 161.3848 269.1606 0)
			(effects
				(font
					(size 1.27 1.27)
				)
				(justify right)
			)
		)
	)
	(global_label "IN1"
		(shape input)
		(at 58.42 228.6 180)
		(fields_autoplaced yes)
		(effects
			(font
				(size 1.27 1.27)
			)
			(justify right)
		)
		(property "Intersheetrefs" "${INTERSHEET_REFS}"
			(at 52.951 228.6794 0)
			(effects
				(font
					(size 1.27 1.27)
				)
				(justify right)
			)
		)
	)
	(global_label "USER_IN"
		(shape input)
		(at 60.96 236.22 180)
		(fields_autoplaced yes)
		(effects
			(font
				(size 1.27 1.27)
			)
			(justify right)
		)
		(property "Intersheetrefs" "${INTERSHEET_REFS}"
			(at 50.7671 236.22 0)
			(effects
				(font
					(size 1.27 1.27)
				)
				(justify right)
			)
		)
	)
	(global_label "IN2"
		(shape input)
		(at 58.42 231.14 180)
		(fields_autoplaced yes)
		(effects
			(font
				(size 1.27 1.27)
			)
			(justify right)
		)
		(property "Intersheetrefs" "${INTERSHEET_REFS}"
			(at 52.951 231.0606 0)
			(effects
				(font
					(size 1.27 1.27)
				)
				(justify right)
			)
		)
	)
	(hierarchical_label "PWR{I^{2}C}"
		(shape bidirectional)
		(at 27.94 233.68 180)
		(effects
			(font
				(size 1.27 1.27)
			)
			(justify right)
		)
	)
	(hierarchical_label "PWR{I^{2}C}"
		(shape bidirectional)
		(at 232.41 257.81 180)
		(effects
			(font
				(size 1.27 1.27)
			)
			(justify right)
		)
	)
	(hierarchical_label "PWR{I^{2}C}"
		(shape bidirectional)
		(at 339.09 153.67 180)
		(effects
			(font
				(size 1.27 1.27)
			)
			(justify right)
		)
	)
	(hierarchical_label "PWR{I^{2}C}"
		(shape bidirectional)
		(at 191.77 105.41 180)
		(effects
			(font
				(size 1.27 1.27)
			)
			(justify right)
		)
	)
	(symbol
		(lib_id "antmicroTestPoints:TP_1mm_SMD")
		(at 133.35 41.91 90)
		(unit 1)
		(exclude_from_sim no)
		(in_bom no)
		(on_board yes)
		(dnp no)
		(property "Reference" "TP16"
			(at 133.35 36.9372 90)
			(effects
				(font
					(size 1.27 1.27)
				)
			)
		)
		(property "Value" "TP_1mm_SMD"
			(at 140.97 26.67 0)
			(effects
				(font
					(size 1.27 1.27)
					(thickness 0.15)
				)
				(justify left bottom)
				(hide yes)
			)
		)
		(property "Footprint" "antmicro-footprints:TP_SMD_1mm"
			(at 143.51 26.67 0)
			(effects
				(font
					(size 1.27 1.27)
					(thickness 0.15)
				)
				(justify left bottom)
				(hide yes)
			)
		)
		(property "Datasheet" ""
			(at 146.05 26.67 0)
			(effects
				(font
					(size 1.27 1.27)
					(thickness 0.15)
				)
				(justify left bottom)
				(hide yes)
			)
		)
		(property "Description" ""
			(at 133.35 41.91 0)
			(effects
				(font
					(size 1.27 1.27)
				)
				(hide yes)
			)
		)
		(property "MPN" ""
			(at 133.35 41.91 0)
			(effects
				(font
					(size 1.27 1.27)
				)
				(hide yes)
			)
		)
		(property "Manufacturer" ""
			(at 133.35 41.91 0)
			(effects
				(font
					(size 1.27 1.27)
				)
				(hide yes)
			)
		)
		(property "Author" "Antmicro"
			(at 148.59 26.67 0)
			(effects
				(font
					(size 1.27 1.27)
					(thickness 0.15)
				)
				(justify left bottom)
				(hide yes)
			)
		)
		(property "License" "Apache-2.0"
			(at 151.13 26.67 0)
			(effects
				(font
					(size 1.27 1.27)
					(thickness 0.15)
				)
				(justify left bottom)
				(hide yes)
			)
		)
		(pin "1"
		)
		(instances
			(project "data-center-rdimm-ddr5-tester"
				(path ""
					(reference "TP16")
					(unit 1)
				)
			)
		)
	)
	(symbol
		(lib_id "antmicropower:+3V3")
		(at 179.07 86.36 0)
		(unit 1)
		(exclude_from_sim no)
		(in_bom yes)
		(on_board yes)
		(dnp no)
		(fields_autoplaced yes)
		(property "Reference" "#PWR0548"
			(at 179.07 90.17 0)
			(effects
				(font
					(size 1.27 1.27)
				)
				(hide yes)
			)
		)
		(property "Value" "+3V3"
			(at 175.895 83.82 0)
			(effects
				(font
					(size 1.27 1.27)
					(thickness 0.15)
				)
				(justify left bottom)
			)
		)
		(property "Footprint" ""
			(at 194.31 93.98 0)
			(effects
				(font
					(size 1.27 1.27)
					(thickness 0.15)
				)
				(justify left bottom)
				(hide yes)
			)
		)
		(property "Datasheet" ""
			(at 194.31 96.52 0)
			(effects
				(font
					(size 1.27 1.27)
					(thickness 0.15)
				)
				(justify left bottom)
				(hide yes)
			)
		)
		(property "Description" ""
			(at 179.07 86.36 0)
			(effects
				(font
					(size 1.27 1.27)
				)
			)
		)
		(property "Author" "Antmicro"
			(at 194.31 88.9 0)
			(effects
				(font
					(size 1.27 1.27)
					(thickness 0.15)
				)
				(justify left bottom)
				(hide yes)
			)
		)
		(property "License" "Apache-2.0"
			(at 194.31 91.44 0)
			(effects
				(font
					(size 1.27 1.27)
					(thickness 0.15)
				)
				(justify left bottom)
				(hide yes)
			)
		)
		(pin "1"
		)
		(instances
			(project "data-center-rdimm-ddr5-tester"
				(path ""
					(reference "#PWR0548")
					(unit 1)
				)
			)
		)
	)
	(symbol
		(lib_id "antmicropower:GND")
		(at 284.48 266.7 0)
		(unit 1)
		(exclude_from_sim no)
		(in_bom yes)
		(on_board yes)
		(dnp no)
		(fields_autoplaced yes)
		(property "Reference" "#PWR0407"
			(at 284.48 273.05 0)
			(effects
				(font
					(size 1.27 1.27)
				)
				(hide yes)
			)
		)
		(property "Value" "GND"
			(at 282.575 271.145 0)
			(effects
				(font
					(size 1.27 1.27)
					(thickness 0.15)
				)
				(justify left bottom)
			)
		)
		(property "Footprint" ""
			(at 293.37 274.32 0)
			(effects
				(font
					(size 1.27 1.27)
					(thickness 0.15)
				)
				(justify left bottom)
				(hide yes)
			)
		)
		(property "Datasheet" ""
			(at 293.37 279.4 0)
			(effects
				(font
					(size 1.27 1.27)
					(thickness 0.15)
				)
				(justify left bottom)
				(hide yes)
			)
		)
		(property "Description" ""
			(at 284.48 266.7 0)
			(effects
				(font
					(size 1.27 1.27)
				)
				(hide yes)
			)
		)
		(property "Author" "Antmicro"
			(at 293.37 271.78 0)
			(effects
				(font
					(size 1.27 1.27)
					(thickness 0.15)
				)
				(justify left bottom)
				(hide yes)
			)
		)
		(property "License" "Apache-2.0"
			(at 293.37 274.32 0)
			(effects
				(font
					(size 1.27 1.27)
					(thickness 0.15)
				)
				(justify left bottom)
				(hide yes)
			)
		)
		(pin "1"
		)
		(instances
			(project "data-center-rdimm-ddr5-tester"
				(path ""
					(reference "#PWR0407")
					(unit 1)
				)
			)
		)
	)
	(symbol
		(lib_id "antmicropower:GND")
		(at 257.81 193.04 0)
		(unit 1)
		(exclude_from_sim no)
		(in_bom yes)
		(on_board yes)
		(dnp no)
		(fields_autoplaced yes)
		(property "Reference" "#PWR0379"
			(at 257.81 199.39 0)
			(effects
				(font
					(size 1.27 1.27)
				)
				(hide yes)
			)
		)
		(property "Value" "GND"
			(at 255.905 197.485 0)
			(effects
				(font
					(size 1.27 1.27)
					(thickness 0.15)
				)
				(justify left bottom)
			)
		)
		(property "Footprint" ""
			(at 266.7 200.66 0)
			(effects
				(font
					(size 1.27 1.27)
					(thickness 0.15)
				)
				(justify left bottom)
				(hide yes)
			)
		)
		(property "Datasheet" ""
			(at 266.7 205.74 0)
			(effects
				(font
					(size 1.27 1.27)
					(thickness 0.15)
				)
				(justify left bottom)
				(hide yes)
			)
		)
		(property "Description" ""
			(at 257.81 193.04 0)
			(effects
				(font
					(size 1.27 1.27)
				)
				(hide yes)
			)
		)
		(property "Author" "Antmicro"
			(at 266.7 198.12 0)
			(effects
				(font
					(size 1.27 1.27)
					(thickness 0.15)
				)
				(justify left bottom)
				(hide yes)
			)
		)
		(property "License" "Apache-2.0"
			(at 266.7 200.66 0)
			(effects
				(font
					(size 1.27 1.27)
					(thickness 0.15)
				)
				(justify left bottom)
				(hide yes)
			)
		)
		(pin "1"
		)
		(instances
			(project "data-center-rdimm-ddr5-tester"
				(path ""
					(reference "#PWR0379")
					(unit 1)
				)
			)
		)
	)
	(symbol
		(lib_id "antmicropower:GND")
		(at 53.34 101.6 0)
		(unit 1)
		(exclude_from_sim no)
		(in_bom yes)
		(on_board yes)
		(dnp no)
		(fields_autoplaced yes)
		(property "Reference" "#PWR0284"
			(at 53.34 107.95 0)
			(effects
				(font
					(size 1.27 1.27)
				)
				(hide yes)
			)
		)
		(property "Value" "GND"
			(at 51.435 106.045 0)
			(effects
				(font
					(size 1.27 1.27)
					(thickness 0.15)
				)
				(justify left bottom)
			)
		)
		(property "Footprint" ""
			(at 62.23 109.22 0)
			(effects
				(font
					(size 1.27 1.27)
					(thickness 0.15)
				)
				(justify left bottom)
				(hide yes)
			)
		)
		(property "Datasheet" ""
			(at 62.23 114.3 0)
			(effects
				(font
					(size 1.27 1.27)
					(thickness 0.15)
				)
				(justify left bottom)
				(hide yes)
			)
		)
		(property "Description" ""
			(at 53.34 101.6 0)
			(effects
				(font
					(size 1.27 1.27)
				)
				(hide yes)
			)
		)
		(property "Author" "Antmicro"
			(at 62.23 106.68 0)
			(effects
				(font
					(size 1.27 1.27)
					(thickness 0.15)
				)
				(justify left bottom)
				(hide yes)
			)
		)
		(property "License" "Apache-2.0"
			(at 62.23 109.22 0)
			(effects
				(font
					(size 1.27 1.27)
					(thickness 0.15)
				)
				(justify left bottom)
				(hide yes)
			)
		)
		(pin "1"
		)
		(instances
			(project "data-center-rdimm-ddr5-tester"
				(path ""
					(reference "#PWR0284")
					(unit 1)
				)
			)
		)
	)
	(symbol
		(lib_id "antmicroCapacitors0402:C_100n_0402")
		(at 53.34 52.07 90)
		(unit 1)
		(exclude_from_sim no)
		(in_bom yes)
		(on_board yes)
		(dnp no)
		(fields_autoplaced yes)
		(property "Reference" "C169"
			(at 55.88 48.2536 90)
			(effects
				(font
					(size 1.27 1.27)
				)
				(justify right)
			)
		)
		(property "Value" "C_100n_0402"
			(at 63.5 31.75 0)
			(effects
				(font
					(size 1.27 1.27)
					(thickness 0.15)
				)
				(justify left bottom)
				(hide yes)
			)
		)
		(property "Footprint" "antmicro-footprints:C_0402_1005Metric"
			(at 66.04 31.75 0)
			(effects
				(font
					(size 1.27 1.27)
					(thickness 0.15)
				)
				(justify left bottom)
				(hide yes)
			)
		)
		(property "Datasheet" "https://www.murata.com/products/productdetail?partno=GRM155R61H104KE14%23"
			(at 68.58 31.75 0)
			(effects
				(font
					(size 1.27 1.27)
					(thickness 0.15)
				)
				(justify left bottom)
				(hide yes)
			)
		)
		(property "Description" ""
			(at 53.34 52.07 0)
			(effects
				(font
					(size 1.27 1.27)
				)
				(hide yes)
			)
		)
		(property "Manufacturer" "Murata"
			(at 73.66 31.75 0)
			(effects
				(font
					(size 1.27 1.27)
					(thickness 0.15)
				)
				(justify left bottom)
				(hide yes)
			)
		)
		(property "MPN" "GRM155R61H104KE14D"
			(at 71.12 31.75 0)
			(effects
				(font
					(size 1.27 1.27)
					(thickness 0.15)
				)
				(justify left bottom)
				(hide yes)
			)
		)
		(property "Val" "100n"
			(at 55.88 50.7936 90)
			(effects
				(font
					(size 1.27 1.27)
					(thickness 0.15)
				)
				(justify right)
			)
		)
		(property "License" "Apache-2.0"
			(at 76.2 31.75 0)
			(effects
				(font
					(size 1.27 1.27)
					(thickness 0.15)
				)
				(justify left bottom)
				(hide yes)
			)
		)
		(property "Author" "Antmicro"
			(at 78.74 31.75 0)
			(effects
				(font
					(size 1.27 1.27)
					(thickness 0.15)
				)
				(justify left bottom)
				(hide yes)
			)
		)
		(property "Voltage" "50V"
			(at 81.28 31.75 0)
			(effects
				(font
					(size 1.27 1.27)
				)
				(justify left bottom)
				(hide yes)
			)
		)
		(property "Dielectric" "X5R"
			(at 83.82 31.75 0)
			(effects
				(font
					(size 1.27 1.27)
				)
				(justify left bottom)
				(hide yes)
			)
		)
		(pin "1"
		)
		(pin "2"
		)
		(instances
			(project "data-center-rdimm-ddr5-tester"
				(path ""
					(reference "C169")
					(unit 1)
				)
			)
		)
	)
	(symbol
		(lib_id "antmicropower:GND")
		(at 335.28 107.95 0)
		(unit 1)
		(exclude_from_sim no)
		(in_bom yes)
		(on_board yes)
		(dnp no)
		(fields_autoplaced yes)
		(property "Reference" "#PWR0541"
			(at 335.28 114.3 0)
			(effects
				(font
					(size 1.27 1.27)
				)
				(hide yes)
			)
		)
		(property "Value" "GND"
			(at 333.375 112.395 0)
			(effects
				(font
					(size 1.27 1.27)
					(thickness 0.15)
				)
				(justify left bottom)
			)
		)
		(property "Footprint" ""
			(at 344.17 115.57 0)
			(effects
				(font
					(size 1.27 1.27)
					(thickness 0.15)
				)
				(justify left bottom)
				(hide yes)
			)
		)
		(property "Datasheet" ""
			(at 344.17 120.65 0)
			(effects
				(font
					(size 1.27 1.27)
					(thickness 0.15)
				)
				(justify left bottom)
				(hide yes)
			)
		)
		(property "Description" ""
			(at 335.28 107.95 0)
			(effects
				(font
					(size 1.27 1.27)
				)
				(hide yes)
			)
		)
		(property "Author" "Antmicro"
			(at 344.17 113.03 0)
			(effects
				(font
					(size 1.27 1.27)
					(thickness 0.15)
				)
				(justify left bottom)
				(hide yes)
			)
		)
		(property "License" "Apache-2.0"
			(at 344.17 115.57 0)
			(effects
				(font
					(size 1.27 1.27)
					(thickness 0.15)
				)
				(justify left bottom)
				(hide yes)
			)
		)
		(pin "1"
		)
		(instances
			(project "data-center-rdimm-ddr5-tester"
				(path ""
					(reference "#PWR0541")
					(unit 1)
				)
			)
		)
	)
	(symbol
		(lib_id "antmicroTransistorsFETsMOSFETsSingle:BSS138PW")
		(at 44.45 171.45 0)
		(unit 1)
		(exclude_from_sim no)
		(in_bom yes)
		(on_board yes)
		(dnp no)
		(fields_autoplaced yes)
		(property "Reference" "Q14"
			(at 55.88 167.64 0)
			(effects
				(font
					(size 1.27 1.27)
					(thickness 0.15)
				)
				(justify left)
			)
		)
		(property "Value" "BSS138PW"
			(at 67.31 180.34 0)
			(effects
				(font
					(size 1.27 1.27)
					(thickness 0.15)
				)
				(justify left bottom)
				(hide yes)
			)
		)
		(property "Footprint" "antmicro-footprints:SC70-3"
			(at 67.31 182.88 0)
			(effects
				(font
					(size 1.27 1.27)
					(thickness 0.15)
				)
				(justify left bottom)
				(hide yes)
			)
		)
		(property "Datasheet" "https://assets.nexperia.com/documents/data-sheet/BSS138PW.pdf"
			(at 67.31 185.42 0)
			(effects
				(font
					(size 1.27 1.27)
					(thickness 0.15)
				)
				(justify left bottom)
				(hide yes)
			)
		)
		(property "Description" ""
			(at 44.45 171.45 0)
			(effects
				(font
					(size 1.27 1.27)
				)
				(hide yes)
			)
		)
		(property "MPN" "BSS138PW"
			(at 55.88 170.18 0)
			(effects
				(font
					(size 1.27 1.27)
					(thickness 0.15)
				)
				(justify left)
			)
		)
		(property "Manufacturer" "Nexperia"
			(at 67.31 190.5 0)
			(effects
				(font
					(size 1.27 1.27)
					(thickness 0.15)
				)
				(justify left bottom)
				(hide yes)
			)
		)
		(property "Author" "Antmicro"
			(at 67.31 193.04 0)
			(effects
				(font
					(size 1.27 1.27)
					(thickness 0.15)
				)
				(justify left bottom)
				(hide yes)
			)
		)
		(property "License" "Apache-2.0"
			(at 67.31 195.58 0)
			(effects
				(font
					(size 1.27 1.27)
					(thickness 0.15)
				)
				(justify left bottom)
				(hide yes)
			)
		)
		(pin "1"
		)
		(pin "3"
		)
		(pin "2"
		)
		(instances
			(project "data-center-rdimm-ddr5-tester"
				(path ""
					(reference "Q14")
					(unit 1)
				)
			)
		)
	)
	(symbol
		(lib_name "MAX16150A_SOT_1")
		(lib_id "antmicroPMICPowerSequencers:MAX16150A_SOT")
		(at 88.9 153.67 0)
		(unit 1)
		(exclude_from_sim no)
		(in_bom yes)
		(on_board yes)
		(dnp no)
		(fields_autoplaced yes)
		(property "Reference" "U22"
			(at 97.79 146.05 0)
			(effects
				(font
					(size 1.27 1.27)
					(thickness 0.15)
				)
			)
		)
		(property "Value" "MAX16150A_SOT"
			(at 120.65 160.02 0)
			(effects
				(font
					(size 1.27 1.27)
					(thickness 0.15)
				)
				(justify left bottom)
				(hide yes)
			)
		)
		(property "Footprint" "antmicro-footprints:SOT-23-6"
			(at 120.65 162.56 0)
			(effects
				(font
					(size 1.27 1.27)
					(thickness 0.15)
				)
				(justify left bottom)
				(hide yes)
			)
		)
		(property "Datasheet" "https://datasheets.maximintegrated.com/en/ds/MAX16150.pdf"
			(at 120.65 165.1 0)
			(effects
				(font
					(size 1.27 1.27)
					(thickness 0.15)
				)
				(justify left bottom)
				(hide yes)
			)
		)
		(property "Description" ""
			(at 88.9 153.67 0)
			(effects
				(font
					(size 1.27 1.27)
				)
				(hide yes)
			)
		)
		(property "Manufacturer" "Maxim Integrated Products"
			(at 120.65 167.64 0)
			(effects
				(font
					(size 1.27 1.27)
					(thickness 0.15)
				)
				(justify left bottom)
				(hide yes)
			)
		)
		(property "MPN" "MAX16150AUT+T"
			(at 97.79 148.59 0)
			(effects
				(font
					(size 1.27 1.27)
					(thickness 0.15)
				)
			)
		)
		(property "License" "Apache-2.0"
			(at 120.65 172.72 0)
			(effects
				(font
					(size 1.27 1.27)
					(thickness 0.15)
				)
				(justify left bottom)
				(hide yes)
			)
		)
		(property "Author" "Antmicro"
			(at 120.65 175.26 0)
			(effects
				(font
					(size 1.27 1.27)
					(thickness 0.15)
				)
				(justify left bottom)
				(hide yes)
			)
		)
		(pin "6"
		)
		(pin "2"
		)
		(pin "1"
		)
		(pin "4"
		)
		(pin "5"
		)
		(pin "3"
		)
		(instances
			(project "data-center-rdimm-ddr5-tester"
				(path ""
					(reference "U22")
					(unit 1)
				)
			)
		)
	)
	(symbol
		(lib_id "antmicroFuses:F_4A_1206")
		(at 59.69 44.45 0)
		(unit 1)
		(exclude_from_sim no)
		(in_bom yes)
		(on_board yes)
		(dnp no)
		(property "Reference" "F1"
			(at 62.23 39.37 0)
			(effects
				(font
					(size 1.27 1.27)
					(thickness 0.15)
				)
			)
		)
		(property "Value" "F_4A_1206"
			(at 80.01 52.07 0)
			(effects
				(font
					(size 1.27 1.27)
					(thickness 0.15)
				)
				(justify left bottom)
				(hide yes)
			)
		)
		(property "Footprint" "antmicro-footprints:F_1206_3216Metric"
			(at 80.01 54.61 0)
			(effects
				(font
					(size 1.27 1.27)
					(thickness 0.15)
				)
				(justify left bottom)
				(hide yes)
			)
		)
		(property "Datasheet" "https://www.littelfuse.com/media?resourcetype=datasheets&itemid=dbe9bcd7-6072-4adf-bf5b-d33e52a6b90f&filename=littelfuse-fuse-466-datasheet"
			(at 80.01 57.15 0)
			(effects
				(font
					(size 1.27 1.27)
					(thickness 0.15)
				)
				(justify left bottom)
				(hide yes)
			)
		)
		(property "Description" ""
			(at 59.69 44.45 0)
			(effects
				(font
					(size 1.27 1.27)
				)
				(hide yes)
			)
		)
		(property "Manufacturer" "Littelfuse"
			(at 80.01 59.69 0)
			(effects
				(font
					(size 1.27 1.27)
					(thickness 0.15)
				)
				(justify left bottom)
				(hide yes)
			)
		)
		(property "MPN" "0466004.NR "
			(at 62.23 41.91 0)
			(effects
				(font
					(size 1.27 1.27)
					(thickness 0.15)
				)
			)
		)
		(property "Author" "Antmicro"
			(at 80.01 64.77 0)
			(effects
				(font
					(size 1.27 1.27)
					(thickness 0.15)
				)
				(justify left bottom)
				(hide yes)
			)
		)
		(property "License" "Apache-2.0"
			(at 80.01 67.31 0)
			(effects
				(font
					(size 1.27 1.27)
					(thickness 0.15)
				)
				(justify left bottom)
				(hide yes)
			)
		)
		(pin "2"
		)
		(pin "1"
		)
		(instances
			(project "data-center-rdimm-ddr5-tester"
				(path ""
					(reference "F1")
					(unit 1)
				)
			)
		)
	)
	(symbol
		(lib_id "antmicropower:GND")
		(at 364.49 86.36 0)
		(unit 1)
		(exclude_from_sim no)
		(in_bom yes)
		(on_board yes)
		(dnp no)
		(fields_autoplaced yes)
		(property "Reference" "#PWR0542"
			(at 364.49 92.71 0)
			(effects
				(font
					(size 1.27 1.27)
				)
				(hide yes)
			)
		)
		(property "Value" "GND"
			(at 362.585 90.805 0)
			(effects
				(font
					(size 1.27 1.27)
					(thickness 0.15)
				)
				(justify left bottom)
			)
		)
		(property "Footprint" ""
			(at 373.38 93.98 0)
			(effects
				(font
					(size 1.27 1.27)
					(thickness 0.15)
				)
				(justify left bottom)
				(hide yes)
			)
		)
		(property "Datasheet" ""
			(at 373.38 99.06 0)
			(effects
				(font
					(size 1.27 1.27)
					(thickness 0.15)
				)
				(justify left bottom)
				(hide yes)
			)
		)
		(property "Description" ""
			(at 364.49 86.36 0)
			(effects
				(font
					(size 1.27 1.27)
				)
				(hide yes)
			)
		)
		(property "Author" "Antmicro"
			(at 373.38 91.44 0)
			(effects
				(font
					(size 1.27 1.27)
					(thickness 0.15)
				)
				(justify left bottom)
				(hide yes)
			)
		)
		(property "License" "Apache-2.0"
			(at 373.38 93.98 0)
			(effects
				(font
					(size 1.27 1.27)
					(thickness 0.15)
				)
				(justify left bottom)
				(hide yes)
			)
		)
		(pin "1"
		)
		(instances
			(project "data-center-rdimm-ddr5-tester"
				(path ""
					(reference "#PWR0542")
					(unit 1)
				)
			)
		)
	)
	(symbol
		(lib_id "antmicroResistors0402:R_47k_0402")
		(at 85.09 152.4 270)
		(mirror x)
		(unit 1)
		(exclude_from_sim no)
		(in_bom yes)
		(on_board yes)
		(dnp no)
		(fields_autoplaced yes)
		(property "Reference" "R149"
			(at 83.439 149.0294 90)
			(effects
				(font
					(size 1.27 1.27)
				)
				(justify right)
			)
		)
		(property "Value" "R_47k_0402"
			(at 72.39 132.08 0)
			(effects
				(font
					(size 1.27 1.27)
					(thickness 0.15)
				)
				(justify left bottom)
				(hide yes)
			)
		)
		(property "Footprint" "antmicro-footprints:R_0402_1005Metric"
			(at 69.85 132.08 0)
			(effects
				(font
					(size 1.27 1.27)
					(thickness 0.15)
				)
				(justify left bottom)
				(hide yes)
			)
		)
		(property "Datasheet" "https://www.bourns.com/docs/product-datasheets/cr.pdf"
			(at 67.31 132.08 0)
			(effects
				(font
					(size 1.27 1.27)
					(thickness 0.15)
				)
				(justify left bottom)
				(hide yes)
			)
		)
		(property "Description" ""
			(at 85.09 152.4 0)
			(effects
				(font
					(size 1.27 1.27)
				)
				(hide yes)
			)
		)
		(property "Manufacturer" "Bourns"
			(at 62.23 132.08 0)
			(effects
				(font
					(size 1.27 1.27)
					(thickness 0.15)
				)
				(justify left bottom)
				(hide yes)
			)
		)
		(property "MPN" "CR0402-FX-4702GLF"
			(at 64.77 132.08 0)
			(effects
				(font
					(size 1.27 1.27)
					(thickness 0.15)
				)
				(justify left bottom)
				(hide yes)
			)
		)
		(property "Val" "47k"
			(at 83.439 151.5597 90)
			(effects
				(font
					(size 1.27 1.27)
					(thickness 0.15)
				)
				(justify right)
			)
		)
		(property "License" "Apache-2.0"
			(at 59.69 132.08 0)
			(effects
				(font
					(size 1.27 1.27)
					(thickness 0.15)
				)
				(justify left bottom)
				(hide yes)
			)
		)
		(property "Author" "Antmicro"
			(at 57.15 132.08 0)
			(effects
				(font
					(size 1.27 1.27)
					(thickness 0.15)
				)
				(justify left bottom)
				(hide yes)
			)
		)
		(property "Tolerance" "1%"
			(at 74.93 132.08 0)
			(effects
				(font
					(size 1.27 1.27)
				)
				(justify left bottom)
				(hide yes)
			)
		)
		(pin "1"
		)
		(pin "2"
		)
		(instances
			(project "data-center-rdimm-ddr5-tester"
				(path ""
					(reference "R149")
					(unit 1)
				)
			)
		)
	)
	(symbol
		(lib_id "antmicropower:GND")
		(at 179.07 96.52 0)
		(mirror y)
		(unit 1)
		(exclude_from_sim no)
		(in_bom yes)
		(on_board yes)
		(dnp no)
		(property "Reference" "#PWR0549"
			(at 179.07 102.87 0)
			(effects
				(font
					(size 1.27 1.27)
				)
				(hide yes)
			)
		)
		(property "Value" "GND"
			(at 179.07 100.076 0)
			(effects
				(font
					(size 1.27 1.27)
					(thickness 0.15)
				)
			)
		)
		(property "Footprint" ""
			(at 170.18 104.14 0)
			(effects
				(font
					(size 1.27 1.27)
					(thickness 0.15)
				)
				(justify left bottom)
				(hide yes)
			)
		)
		(property "Datasheet" ""
			(at 170.18 109.22 0)
			(effects
				(font
					(size 1.27 1.27)
					(thickness 0.15)
				)
				(justify left bottom)
				(hide yes)
			)
		)
		(property "Description" ""
			(at 170.18 111.76 0)
			(effects
				(font
					(size 1.27 1.27)
				)
				(justify left bottom)
				(hide yes)
			)
		)
		(property "Author" "Antmicro"
			(at 170.18 104.14 0)
			(effects
				(font
					(size 1.27 1.27)
					(thickness 0.15)
				)
				(justify left bottom)
				(hide yes)
			)
		)
		(property "License" "Apache-2.0"
			(at 170.18 106.68 0)
			(effects
				(font
					(size 1.27 1.27)
					(thickness 0.15)
				)
				(justify left bottom)
				(hide yes)
			)
		)
		(pin "1"
		)
		(instances
			(project "data-center-rdimm-ddr5-tester"
				(path ""
					(reference "#PWR0549")
					(unit 1)
				)
			)
		)
	)
	(symbol
		(lib_id "antmicropower:VDC")
		(at 142.24 71.12 0)
		(unit 1)
		(exclude_from_sim no)
		(in_bom yes)
		(on_board yes)
		(dnp no)
		(property "Reference" "#PWR0300"
			(at 142.24 73.66 0)
			(effects
				(font
					(size 1.27 1.27)
				)
				(hide yes)
			)
		)
		(property "Value" "VDC"
			(at 142.24 67.31 0)
			(effects
				(font
					(size 1.27 1.27)
				)
			)
		)
		(property "Footprint" ""
			(at 142.24 71.12 0)
			(effects
				(font
					(size 1.27 1.27)
				)
				(hide yes)
			)
		)
		(property "Datasheet" ""
			(at 142.24 71.12 0)
			(effects
				(font
					(size 1.27 1.27)
				)
				(hide yes)
			)
		)
		(property "Description" ""
			(at 142.24 71.12 0)
			(effects
				(font
					(size 1.27 1.27)
				)
				(hide yes)
			)
		)
		(pin "1"
		)
		(instances
			(project "data-center-rdimm-ddr5-tester"
				(path ""
					(reference "#PWR0300")
					(unit 1)
				)
			)
		)
	)
	(symbol
		(lib_id "antmicroPushbuttonSwitches:SW_KMR211NGLFS_SMD")
		(at 69.85 177.8 90)
		(unit 1)
		(exclude_from_sim no)
		(in_bom yes)
		(on_board yes)
		(dnp no)
		(fields_autoplaced yes)
		(property "Reference" "SW5"
			(at 73.406 171.8894 90)
			(effects
				(font
					(size 1.27 1.27)
					(thickness 0.15)
				)
				(justify right)
			)
		)
		(property "Value" "SW_KMR211NGLFS_SMD"
			(at 77.47 152.4 0)
			(effects
				(font
					(size 1.27 1.27)
					(thickness 0.15)
				)
				(justify left bottom)
				(hide yes)
			)
		)
		(property "Footprint" "antmicro-footprints:SW_KMR211NGLFS_SMD"
			(at 80.01 152.4 0)
			(effects
				(font
					(size 1.27 1.27)
					(thickness 0.15)
				)
				(justify left bottom)
				(hide yes)
			)
		)
		(property "Datasheet" "http://www.farnell.com/datasheets/2631211.pdf"
			(at 82.55 152.4 0)
			(effects
				(font
					(size 1.27 1.27)
					(thickness 0.15)
				)
				(justify left bottom)
				(hide yes)
			)
		)
		(property "Description" ""
			(at 69.85 177.8 0)
			(effects
				(font
					(size 1.27 1.27)
				)
				(hide yes)
			)
		)
		(property "MPN" "KMR211NGLFS"
			(at 73.406 174.4131 90)
			(effects
				(font
					(size 1.27 1.27)
					(thickness 0.15)
				)
				(justify right)
			)
		)
		(property "Manufacturer" "C&K"
			(at 85.09 152.4 0)
			(effects
				(font
					(size 1.27 1.27)
					(thickness 0.15)
				)
				(justify left bottom)
				(hide yes)
			)
		)
		(property "Author" "Antmicro"
			(at 87.63 152.4 0)
			(effects
				(font
					(size 1.27 1.27)
					(thickness 0.15)
				)
				(justify left bottom)
				(hide yes)
			)
		)
		(property "License" "Apache-2.0"
			(at 90.17 152.4 0)
			(effects
				(font
					(size 1.27 1.27)
					(thickness 0.15)
				)
				(justify left bottom)
				(hide yes)
			)
		)
		(pin "1"
		)
		(pin "2"
		)
		(pin "3"
		)
		(pin "4"
		)
		(instances
			(project "data-center-rdimm-ddr5-tester"
				(path ""
					(reference "SW5")
					(unit 1)
				)
			)
		)
	)
	(symbol
		(lib_id "antmicroCapacitors0402:C_100n_0402")
		(at 250.19 93.98 270)
		(mirror x)
		(unit 1)
		(exclude_from_sim no)
		(in_bom yes)
		(on_board yes)
		(dnp no)
		(property "Reference" "C332"
			(at 248.92 89.535 90)
			(effects
				(font
					(size 1.27 1.27)
				)
				(justify right)
			)
		)
		(property "Value" "C_100n_0402"
			(at 240.03 73.66 0)
			(effects
				(font
					(size 1.27 1.27)
					(thickness 0.15)
				)
				(justify left bottom)
				(hide yes)
			)
		)
		(property "Footprint" "antmicro-footprints:C_0402_1005Metric"
			(at 237.49 73.66 0)
			(effects
				(font
					(size 1.27 1.27)
					(thickness 0.15)
				)
				(justify left bottom)
				(hide yes)
			)
		)
		(property "Datasheet" "https://www.murata.com/products/productdetail?partno=GRM155R61H104KE14%23"
			(at 234.95 73.66 0)
			(effects
				(font
					(size 1.27 1.27)
					(thickness 0.15)
				)
				(justify left bottom)
				(hide yes)
			)
		)
		(property "Description" ""
			(at 250.19 93.98 0)
			(effects
				(font
					(size 1.27 1.27)
				)
			)
		)
		(property "Manufacturer" "Murata"
			(at 229.87 73.66 0)
			(effects
				(font
					(size 1.27 1.27)
					(thickness 0.15)
				)
				(justify left bottom)
				(hide yes)
			)
		)
		(property "MPN" "GRM155R61H104KE14D"
			(at 232.41 73.66 0)
			(effects
				(font
					(size 1.27 1.27)
					(thickness 0.15)
				)
				(justify left bottom)
				(hide yes)
			)
		)
		(property "Val" "100n"
			(at 248.92 93.345 90)
			(effects
				(font
					(size 1.27 1.27)
					(thickness 0.15)
				)
				(justify right)
			)
		)
		(property "License" "Apache-2.0"
			(at 227.33 73.66 0)
			(effects
				(font
					(size 1.27 1.27)
					(thickness 0.15)
				)
				(justify left bottom)
				(hide yes)
			)
		)
		(property "Author" "Antmicro"
			(at 224.79 73.66 0)
			(effects
				(font
					(size 1.27 1.27)
					(thickness 0.15)
				)
				(justify left bottom)
				(hide yes)
			)
		)
		(property "Voltage" "50V"
			(at 222.25 73.66 0)
			(effects
				(font
					(size 1.27 1.27)
				)
				(justify left bottom)
				(hide yes)
			)
		)
		(property "Dielectric" "X5R"
			(at 219.71 73.66 0)
			(effects
				(font
					(size 1.27 1.27)
				)
				(justify left bottom)
				(hide yes)
			)
		)
		(pin "1"
		)
		(pin "2"
		)
		(instances
			(project "data-center-rdimm-ddr5-tester"
				(path ""
					(reference "C332")
					(unit 1)
				)
			)
		)
	)
	(symbol
		(lib_id "antmicroTransistorsFETsMOSFETsSingle:BSS138PW")
		(at 327.66 97.79 0)
		(unit 1)
		(exclude_from_sim no)
		(in_bom yes)
		(on_board yes)
		(dnp no)
		(property "Reference" "Q28"
			(at 339.09 93.98 0)
			(effects
				(font
					(size 1.27 1.27)
				)
				(justify left)
			)
		)
		(property "Value" "BSS138PW"
			(at 339.09 97.1549 0)
			(effects
				(font
					(size 1.27 1.27)
					(thickness 0.15)
				)
				(justify left)
			)
		)
		(property "Footprint" "antmicro-footprints:SC70-3"
			(at 350.52 109.22 0)
			(effects
				(font
					(size 1.27 1.27)
					(thickness 0.15)
				)
				(justify left bottom)
				(hide yes)
			)
		)
		(property "Datasheet" "https://assets.nexperia.com/documents/data-sheet/BSS138PW.pdf"
			(at 350.52 111.76 0)
			(effects
				(font
					(size 1.27 1.27)
					(thickness 0.15)
				)
				(justify left bottom)
				(hide yes)
			)
		)
		(property "Description" ""
			(at 327.66 97.79 0)
			(effects
				(font
					(size 1.27 1.27)
				)
				(hide yes)
			)
		)
		(property "MPN" "BSS138PW"
			(at 350.52 114.3 0)
			(effects
				(font
					(size 1.27 1.27)
					(thickness 0.15)
				)
				(justify left bottom)
				(hide yes)
			)
		)
		(property "Manufacturer" "Nexperia"
			(at 350.52 116.84 0)
			(effects
				(font
					(size 1.27 1.27)
					(thickness 0.15)
				)
				(justify left bottom)
				(hide yes)
			)
		)
		(property "Author" "Antmicro"
			(at 350.52 119.38 0)
			(effects
				(font
					(size 1.27 1.27)
					(thickness 0.15)
				)
				(justify left bottom)
				(hide yes)
			)
		)
		(property "License" "Apache-2.0"
			(at 350.52 121.92 0)
			(effects
				(font
					(size 1.27 1.27)
					(thickness 0.15)
				)
				(justify left bottom)
				(hide yes)
			)
		)
		(pin "1"
		)
		(pin "2"
		)
		(pin "3"
		)
		(instances
			(project "data-center-rdimm-ddr5-tester"
				(path ""
					(reference "Q28")
					(unit 1)
				)
			)
		)
	)
	(symbol
		(lib_id "antmicroResistors0402:R_330R_0402")
		(at 107.95 236.22 0)
		(unit 1)
		(exclude_from_sim no)
		(in_bom yes)
		(on_board yes)
		(dnp no)
		(fields_autoplaced yes)
		(property "Reference" "R87"
			(at 110.49 229.87 0)
			(effects
				(font
					(size 1.27 1.27)
					(thickness 0.15)
				)
			)
		)
		(property "Value" "R_330R_0402"
			(at 128.27 248.92 0)
			(effects
				(font
					(size 1.27 1.27)
					(thickness 0.15)
				)
				(justify left bottom)
				(hide yes)
			)
		)
		(property "Footprint" "antmicro-footprints:R_0402_1005Metric"
			(at 128.27 251.46 0)
			(effects
				(font
					(size 1.27 1.27)
					(thickness 0.15)
				)
				(justify left bottom)
				(hide yes)
			)
		)
		(property "Datasheet" "https://www.bourns.com/docs/product-datasheets/cr.pdf"
			(at 128.27 254 0)
			(effects
				(font
					(size 1.27 1.27)
					(thickness 0.15)
				)
				(justify left bottom)
				(hide yes)
			)
		)
		(property "Description" ""
			(at 107.95 236.22 0)
			(effects
				(font
					(size 1.27 1.27)
				)
				(hide yes)
			)
		)
		(property "MPN" "CR0402-FX-3300GLF"
			(at 128.27 256.54 0)
			(effects
				(font
					(size 1.27 1.27)
					(thickness 0.15)
				)
				(justify left bottom)
				(hide yes)
			)
		)
		(property "Manufacturer" "Bourns"
			(at 128.27 259.08 0)
			(effects
				(font
					(size 1.27 1.27)
					(thickness 0.15)
				)
				(justify left bottom)
				(hide yes)
			)
		)
		(property "License" "Apache-2.0"
			(at 128.27 261.62 0)
			(effects
				(font
					(size 1.27 1.27)
					(thickness 0.15)
				)
				(justify left bottom)
				(hide yes)
			)
		)
		(property "Author" "Antmicro"
			(at 128.27 264.16 0)
			(effects
				(font
					(size 1.27 1.27)
					(thickness 0.15)
				)
				(justify left bottom)
				(hide yes)
			)
		)
		(property "Val" "330R"
			(at 110.49 232.41 0)
			(effects
				(font
					(size 1.27 1.27)
					(thickness 0.15)
				)
			)
		)
		(property "Tolerance" "1%"
			(at 128.27 246.38 0)
			(effects
				(font
					(size 1.27 1.27)
				)
				(justify left bottom)
				(hide yes)
			)
		)
		(pin "2"
		)
		(pin "1"
		)
		(instances
			(project "data-center-rdimm-ddr5-tester"
				(path ""
					(reference "R87")
					(unit 1)
				)
			)
		)
	)
	(symbol
		(lib_id "antmicropower:GND")
		(at 198.12 175.26 0)
		(mirror y)
		(unit 1)
		(exclude_from_sim no)
		(in_bom yes)
		(on_board yes)
		(dnp no)
		(fields_autoplaced yes)
		(property "Reference" "#PWR0369"
			(at 198.12 181.61 0)
			(effects
				(font
					(size 1.27 1.27)
				)
				(hide yes)
			)
		)
		(property "Value" "GND"
			(at 200.025 179.705 0)
			(effects
				(font
					(size 1.27 1.27)
					(thickness 0.15)
				)
				(justify left bottom)
			)
		)
		(property "Footprint" ""
			(at 189.23 182.88 0)
			(effects
				(font
					(size 1.27 1.27)
					(thickness 0.15)
				)
				(justify left bottom)
				(hide yes)
			)
		)
		(property "Datasheet" ""
			(at 189.23 187.96 0)
			(effects
				(font
					(size 1.27 1.27)
					(thickness 0.15)
				)
				(justify left bottom)
				(hide yes)
			)
		)
		(property "Description" ""
			(at 198.12 175.26 0)
			(effects
				(font
					(size 1.27 1.27)
				)
				(hide yes)
			)
		)
		(property "Author" "Antmicro"
			(at 189.23 180.34 0)
			(effects
				(font
					(size 1.27 1.27)
					(thickness 0.15)
				)
				(justify left bottom)
				(hide yes)
			)
		)
		(property "License" "Apache-2.0"
			(at 189.23 182.88 0)
			(effects
				(font
					(size 1.27 1.27)
					(thickness 0.15)
				)
				(justify left bottom)
				(hide yes)
			)
		)
		(pin "1"
		)
		(instances
			(project "data-center-rdimm-ddr5-tester"
				(path ""
					(reference "#PWR0369")
					(unit 1)
				)
			)
		)
	)
	(symbol
		(lib_id "antmicroTestPoints:TP_1mm_SMD")
		(at 240.03 36.83 0)
		(unit 1)
		(exclude_from_sim no)
		(in_bom no)
		(on_board yes)
		(dnp no)
		(property "Reference" "TP19"
			(at 241.3 38.735 0)
			(effects
				(font
					(size 1.27 1.27)
				)
				(justify left)
			)
		)
		(property "Value" "TP_1mm_SMD"
			(at 255.27 44.45 0)
			(effects
				(font
					(size 1.27 1.27)
					(thickness 0.15)
				)
				(justify left bottom)
				(hide yes)
			)
		)
		(property "Footprint" "antmicro-footprints:TP_SMD_1mm"
			(at 255.27 46.99 0)
			(effects
				(font
					(size 1.27 1.27)
					(thickness 0.15)
				)
				(justify left bottom)
				(hide yes)
			)
		)
		(property "Datasheet" ""
			(at 255.27 49.53 0)
			(effects
				(font
					(size 1.27 1.27)
					(thickness 0.15)
				)
				(justify left bottom)
				(hide yes)
			)
		)
		(property "Description" ""
			(at 240.03 36.83 0)
			(effects
				(font
					(size 1.27 1.27)
				)
				(hide yes)
			)
		)
		(property "MPN" ""
			(at 240.03 36.83 0)
			(effects
				(font
					(size 1.27 1.27)
				)
				(hide yes)
			)
		)
		(property "Manufacturer" ""
			(at 240.03 36.83 0)
			(effects
				(font
					(size 1.27 1.27)
				)
				(hide yes)
			)
		)
		(property "Author" "Antmicro"
			(at 255.27 52.07 0)
			(effects
				(font
					(size 1.27 1.27)
					(thickness 0.15)
				)
				(justify left bottom)
				(hide yes)
			)
		)
		(property "License" "Apache-2.0"
			(at 255.27 54.61 0)
			(effects
				(font
					(size 1.27 1.27)
					(thickness 0.15)
				)
				(justify left bottom)
				(hide yes)
			)
		)
		(pin "1"
		)
		(instances
			(project "data-center-rdimm-ddr5-tester"
				(path ""
					(reference "TP19")
					(unit 1)
				)
			)
		)
	)
	(symbol
		(lib_id "antmicropower:GND")
		(at 339.09 45.72 0)
		(unit 1)
		(exclude_from_sim no)
		(in_bom yes)
		(on_board yes)
		(dnp no)
		(fields_autoplaced yes)
		(property "Reference" "#PWR0365"
			(at 339.09 52.07 0)
			(effects
				(font
					(size 1.27 1.27)
				)
				(hide yes)
			)
		)
		(property "Value" "GND"
			(at 337.185 50.165 0)
			(effects
				(font
					(size 1.27 1.27)
					(thickness 0.15)
				)
				(justify left bottom)
			)
		)
		(property "Footprint" ""
			(at 347.98 53.34 0)
			(effects
				(font
					(size 1.27 1.27)
					(thickness 0.15)
				)
				(justify left bottom)
				(hide yes)
			)
		)
		(property "Datasheet" ""
			(at 347.98 58.42 0)
			(effects
				(font
					(size 1.27 1.27)
					(thickness 0.15)
				)
				(justify left bottom)
				(hide yes)
			)
		)
		(property "Description" ""
			(at 339.09 45.72 0)
			(effects
				(font
					(size 1.27 1.27)
				)
				(hide yes)
			)
		)
		(property "Author" "Antmicro"
			(at 347.98 50.8 0)
			(effects
				(font
					(size 1.27 1.27)
					(thickness 0.15)
				)
				(justify left bottom)
				(hide yes)
			)
		)
		(property "License" "Apache-2.0"
			(at 347.98 53.34 0)
			(effects
				(font
					(size 1.27 1.27)
					(thickness 0.15)
				)
				(justify left bottom)
				(hide yes)
			)
		)
		(pin "1"
		)
		(instances
			(project "data-center-rdimm-ddr5-tester"
				(path ""
					(reference "#PWR0365")
					(unit 1)
				)
			)
		)
	)
	(symbol
		(lib_id "antmicroTransistorsFETsMOSFETsSingle:BSS138PW")
		(at 307.34 50.8 0)
		(unit 1)
		(exclude_from_sim no)
		(in_bom yes)
		(on_board yes)
		(dnp no)
		(property "Reference" "Q15"
			(at 317.5 45.72 0)
			(effects
				(font
					(size 1.27 1.27)
					(thickness 0.15)
				)
				(justify left)
			)
		)
		(property "Value" "BSS138PW"
			(at 330.2 59.69 0)
			(effects
				(font
					(size 1.27 1.27)
					(thickness 0.15)
				)
				(justify left bottom)
				(hide yes)
			)
		)
		(property "Footprint" "antmicro-footprints:SC70-3"
			(at 330.2 62.23 0)
			(effects
				(font
					(size 1.27 1.27)
					(thickness 0.15)
				)
				(justify left bottom)
				(hide yes)
			)
		)
		(property "Datasheet" "https://assets.nexperia.com/documents/data-sheet/BSS138PW.pdf"
			(at 330.2 64.77 0)
			(effects
				(font
					(size 1.27 1.27)
					(thickness 0.15)
				)
				(justify left bottom)
				(hide yes)
			)
		)
		(property "Description" ""
			(at 307.34 50.8 0)
			(effects
				(font
					(size 1.27 1.27)
				)
				(hide yes)
			)
		)
		(property "MPN" "BSS138PW"
			(at 303.53 54.61 0)
			(effects
				(font
					(size 1.27 1.27)
					(thickness 0.15)
				)
				(justify left)
			)
		)
		(property "Manufacturer" "Nexperia"
			(at 330.2 69.85 0)
			(effects
				(font
					(size 1.27 1.27)
					(thickness 0.15)
				)
				(justify left bottom)
				(hide yes)
			)
		)
		(property "Author" "Antmicro"
			(at 330.2 72.39 0)
			(effects
				(font
					(size 1.27 1.27)
					(thickness 0.15)
				)
				(justify left bottom)
				(hide yes)
			)
		)
		(property "License" "Apache-2.0"
			(at 330.2 74.93 0)
			(effects
				(font
					(size 1.27 1.27)
					(thickness 0.15)
				)
				(justify left bottom)
				(hide yes)
			)
		)
		(pin "1"
		)
		(pin "3"
		)
		(pin "2"
		)
		(instances
			(project "data-center-rdimm-ddr5-tester"
				(path ""
					(reference "Q15")
					(unit 1)
				)
			)
		)
	)
	(symbol
		(lib_id "antmicropower:PWR_FLAG")
		(at 231.14 35.56 0)
		(unit 1)
		(exclude_from_sim no)
		(in_bom yes)
		(on_board yes)
		(dnp no)
		(fields_autoplaced yes)
		(property "Reference" "#FLG0120"
			(at 231.14 33.655 0)
			(effects
				(font
					(size 1.27 1.27)
				)
				(hide yes)
			)
		)
		(property "Value" "PWR_FLAG"
			(at 231.14 31.9842 0)
			(effects
				(font
					(size 1.27 1.27)
				)
			)
		)
		(property "Footprint" ""
			(at 231.14 35.56 0)
			(effects
				(font
					(size 1.27 1.27)
				)
				(hide yes)
			)
		)
		(property "Datasheet" ""
			(at 231.14 35.56 0)
			(effects
				(font
					(size 1.27 1.27)
				)
				(hide yes)
			)
		)
		(property "Description" ""
			(at 231.14 35.56 0)
			(effects
				(font
					(size 1.27 1.27)
				)
				(hide yes)
			)
		)
		(pin "1"
		)
		(instances
			(project "data-center-rdimm-ddr5-tester"
				(path ""
					(reference "#FLG0120")
					(unit 1)
				)
			)
		)
	)
	(symbol
		(lib_id "antmicropower:+3V3_AON")
		(at 63.5 214.63 0)
		(mirror y)
		(unit 1)
		(exclude_from_sim no)
		(in_bom yes)
		(on_board yes)
		(dnp no)
		(property "Reference" "#PWR0297"
			(at 63.5 218.44 0)
			(effects
				(font
					(size 1.27 1.27)
				)
				(hide yes)
			)
		)
		(property "Value" "+3V3_AON"
			(at 68.58 210.82 0)
			(effects
				(font
					(size 1.27 1.27)
				)
			)
		)
		(property "Footprint" ""
			(at 63.5 214.63 0)
			(effects
				(font
					(size 1.27 1.27)
				)
				(hide yes)
			)
		)
		(property "Datasheet" ""
			(at 63.5 214.63 0)
			(effects
				(font
					(size 1.27 1.27)
				)
				(hide yes)
			)
		)
		(property "Description" ""
			(at 63.5 214.63 0)
			(effects
				(font
					(size 1.27 1.27)
				)
				(hide yes)
			)
		)
		(pin "1"
		)
		(instances
			(project "data-center-rdimm-ddr5-tester"
				(path ""
					(reference "#PWR0297")
					(unit 1)
				)
			)
		)
	)
	(symbol
		(lib_id "antmicropower:VDC")
		(at 304.8 76.2 0)
		(unit 1)
		(exclude_from_sim no)
		(in_bom yes)
		(on_board yes)
		(dnp no)
		(fields_autoplaced yes)
		(property "Reference" "#PWR0459"
			(at 304.8 78.74 0)
			(effects
				(font
					(size 1.27 1.27)
				)
				(hide yes)
			)
		)
		(property "Value" "VDC"
			(at 304.8 71.755 0)
			(effects
				(font
					(size 1.27 1.27)
				)
			)
		)
		(property "Footprint" ""
			(at 304.8 76.2 0)
			(effects
				(font
					(size 1.27 1.27)
				)
				(hide yes)
			)
		)
		(property "Datasheet" ""
			(at 304.8 76.2 0)
			(effects
				(font
					(size 1.27 1.27)
				)
				(hide yes)
			)
		)
		(property "Description" ""
			(at 304.8 76.2 0)
			(effects
				(font
					(size 1.27 1.27)
				)
				(hide yes)
			)
		)
		(pin "1"
		)
		(instances
			(project "data-center-rdimm-ddr5-tester"
				(path ""
					(reference "#PWR0459")
					(unit 1)
				)
			)
		)
	)
	(symbol
		(lib_id "antmicroTestPoints:TP_1206_SMD_RCW-0C")
		(at 351.79 243.84 0)
		(unit 1)
		(exclude_from_sim no)
		(in_bom yes)
		(on_board yes)
		(dnp no)
		(fields_autoplaced yes)
		(property "Reference" "TP21"
			(at 356.362 243.0094 0)
			(effects
				(font
					(size 1.27 1.27)
					(thickness 0.15)
				)
				(justify left)
			)
		)
		(property "Value" "TP_1206_SMD_RCW-0C"
			(at 356.362 245.5331 0)
			(effects
				(font
					(size 1.27 1.27)
					(thickness 0.15)
				)
				(justify left)
				(hide yes)
			)
		)
		(property "Footprint" "antmicro-footprints:TP_1206_SMD_RCW-0C"
			(at 369.57 254 0)
			(effects
				(font
					(size 1.27 1.27)
					(thickness 0.15)
				)
				(justify left bottom)
				(hide yes)
			)
		)
		(property "Datasheet" "https://www.te.com/commerce/DocumentDelivery/DDEController?Action=srchrtrv&DocNm=1773266&DocType=DS&DocLang=English"
			(at 369.57 256.54 0)
			(effects
				(font
					(size 1.27 1.27)
					(thickness 0.15)
				)
				(justify left bottom)
				(hide yes)
			)
		)
		(property "Description" ""
			(at 351.79 243.84 0)
			(effects
				(font
					(size 1.27 1.27)
				)
				(hide yes)
			)
		)
		(property "MPN" "RCW-0C"
			(at 369.57 259.08 0)
			(effects
				(font
					(size 1.27 1.27)
					(thickness 0.15)
				)
				(justify left bottom)
				(hide yes)
			)
		)
		(property "Manufacturer" "TE Connectivity"
			(at 369.57 261.62 0)
			(effects
				(font
					(size 1.27 1.27)
					(thickness 0.15)
				)
				(justify left bottom)
				(hide yes)
			)
		)
		(property "Author" "Antmicro"
			(at 369.57 264.16 0)
			(effects
				(font
					(size 1.27 1.27)
					(thickness 0.15)
				)
				(justify left bottom)
				(hide yes)
			)
		)
		(property "License" "Apache-2.0"
			(at 369.57 266.7 0)
			(effects
				(font
					(size 1.27 1.27)
					(thickness 0.15)
				)
				(justify left bottom)
				(hide yes)
			)
		)
		(pin "1"
		)
		(instances
			(project "data-center-rdimm-ddr5-tester"
				(path ""
					(reference "TP21")
					(unit 1)
				)
			)
		)
	)
	(symbol
		(lib_id "antmicroSlideSwitches:SW_CVS-08TB")
		(at 78.74 223.52 0)
		(unit 1)
		(exclude_from_sim no)
		(in_bom yes)
		(on_board yes)
		(dnp no)
		(fields_autoplaced yes)
		(property "Reference" "SW4"
			(at 85.0917 215.9 0)
			(effects
				(font
					(size 1.27 1.27)
					(thickness 0.15)
				)
			)
		)
		(property "Value" "SW_CVS-08TB"
			(at 85.0917 218.44 0)
			(effects
				(font
					(size 1.27 1.27)
					(thickness 0.15)
				)
			)
		)
		(property "Footprint" "antmicro-footprints:SW_DIP_SPSTx08_Slide_Copal_CVS-08xB_W5.9mm_P1mm"
			(at 105.41 231.14 0)
			(effects
				(font
					(size 1.27 1.27)
					(thickness 0.15)
				)
				(justify left bottom)
				(hide yes)
			)
		)
		(property "Datasheet" "https://www.mouser.com/datasheet/2/972/cvs-1827291.pdf"
			(at 105.41 233.68 0)
			(effects
				(font
					(size 1.27 1.27)
					(thickness 0.15)
				)
				(justify left bottom)
				(hide yes)
			)
		)
		(property "Description" ""
			(at 78.74 223.52 0)
			(effects
				(font
					(size 1.27 1.27)
				)
				(hide yes)
			)
		)
		(property "MPN" "CVS-08TB"
			(at 105.41 236.22 0)
			(effects
				(font
					(size 1.27 1.27)
					(thickness 0.15)
				)
				(justify left bottom)
				(hide yes)
			)
		)
		(property "Manufacturer" "Nidec Components"
			(at 105.41 238.76 0)
			(effects
				(font
					(size 1.27 1.27)
					(thickness 0.15)
				)
				(justify left bottom)
				(hide yes)
			)
		)
		(property "Author" "Antmicro"
			(at 105.41 241.3 0)
			(effects
				(font
					(size 1.27 1.27)
					(thickness 0.15)
				)
				(justify left bottom)
				(hide yes)
			)
		)
		(property "License" "Apache-2.0"
			(at 105.41 243.84 0)
			(effects
				(font
					(size 1.27 1.27)
					(thickness 0.15)
				)
				(justify left bottom)
				(hide yes)
			)
		)
		(pin "8"
		)
		(pin "16"
		)
		(pin "13"
		)
		(pin "3"
		)
		(pin "5"
		)
		(pin "4"
		)
		(pin "2"
		)
		(pin "10"
		)
		(pin "17"
		)
		(pin "9"
		)
		(pin "11"
		)
		(pin "7"
		)
		(pin "6"
		)
		(pin "1"
		)
		(pin "15"
		)
		(pin "14"
		)
		(pin "12"
		)
		(instances
			(project "data-center-rdimm-ddr5-tester"
				(path ""
					(reference "SW4")
					(unit 1)
				)
			)
		)
	)
	(symbol
		(lib_id "antmicroPMICVoltageRegulatorsLinear:NCP718BSN330T1G")
		(at 200.66 36.83 0)
		(unit 1)
		(exclude_from_sim no)
		(in_bom yes)
		(on_board yes)
		(dnp no)
		(fields_autoplaced yes)
		(property "Reference" "U21"
			(at 210.82 29.21 0)
			(effects
				(font
					(size 1.27 1.27)
					(thickness 0.15)
				)
			)
		)
		(property "Value" "NCP718BSN330T1G"
			(at 236.22 43.18 0)
			(effects
				(font
					(size 1.27 1.27)
					(thickness 0.15)
				)
				(justify left bottom)
				(hide yes)
			)
		)
		(property "Footprint" "antmicro-footprints:SOT-23-5"
			(at 236.22 45.72 0)
			(effects
				(font
					(size 1.27 1.27)
					(thickness 0.15)
				)
				(justify left bottom)
				(hide yes)
			)
		)
		(property "Datasheet" "https://www.mouser.com/datasheet/2/308/NCP718_D-1224359.pdf"
			(at 236.22 48.26 0)
			(effects
				(font
					(size 1.27 1.27)
					(thickness 0.15)
				)
				(justify left bottom)
				(hide yes)
			)
		)
		(property "Description" ""
			(at 200.66 36.83 0)
			(effects
				(font
					(size 1.27 1.27)
				)
				(hide yes)
			)
		)
		(property "MPN" "NCP718BSN330T1G"
			(at 210.82 31.75 0)
			(effects
				(font
					(size 1.27 1.27)
					(thickness 0.15)
				)
			)
		)
		(property "Manufacturer" "ON Semiconductor"
			(at 236.22 53.34 0)
			(effects
				(font
					(size 1.27 1.27)
					(thickness 0.15)
				)
				(justify left bottom)
				(hide yes)
			)
		)
		(property "Author" "Antmicro"
			(at 236.22 55.88 0)
			(effects
				(font
					(size 1.27 1.27)
					(thickness 0.15)
				)
				(justify left bottom)
				(hide yes)
			)
		)
		(property "License" "Apache-2.0"
			(at 236.22 58.42 0)
			(effects
				(font
					(size 1.27 1.27)
					(thickness 0.15)
				)
				(justify left bottom)
				(hide yes)
			)
		)
		(pin "2"
		)
		(pin "1"
		)
		(pin "4"
		)
		(pin "3"
		)
		(pin "5"
		)
		(instances
			(project "data-center-rdimm-ddr5-tester"
				(path ""
					(reference "U21")
					(unit 1)
				)
			)
		)
	)
	(symbol
		(lib_id "antmicropower:PWR_FLAG")
		(at 62.23 76.2 0)
		(unit 1)
		(exclude_from_sim no)
		(in_bom yes)
		(on_board yes)
		(dnp no)
		(fields_autoplaced yes)
		(property "Reference" "#FLG020"
			(at 62.23 74.295 0)
			(effects
				(font
					(size 1.27 1.27)
				)
				(hide yes)
			)
		)
		(property "Value" "PWR_FLAG"
			(at 62.23 72.6242 0)
			(effects
				(font
					(size 1.27 1.27)
				)
			)
		)
		(property "Footprint" ""
			(at 62.23 76.2 0)
			(effects
				(font
					(size 1.27 1.27)
				)
				(hide yes)
			)
		)
		(property "Datasheet" ""
			(at 62.23 76.2 0)
			(effects
				(font
					(size 1.27 1.27)
				)
				(hide yes)
			)
		)
		(property "Description" ""
			(at 62.23 76.2 0)
			(effects
				(font
					(size 1.27 1.27)
				)
				(hide yes)
			)
		)
		(pin "1"
		)
		(instances
			(project "data-center-rdimm-ddr5-tester"
				(path ""
					(reference "#FLG020")
					(unit 1)
				)
			)
		)
	)
	(symbol
		(lib_id "antmicroFuses:F_4A_1206")
		(at 67.31 77.47 0)
		(unit 1)
		(exclude_from_sim no)
		(in_bom yes)
		(on_board yes)
		(dnp no)
		(fields_autoplaced yes)
		(property "Reference" "F2"
			(at 69.85 73.66 0)
			(effects
				(font
					(size 1.27 1.27)
					(thickness 0.15)
				)
			)
		)
		(property "Value" "F_4A_1206"
			(at 87.63 85.09 0)
			(effects
				(font
					(size 1.27 1.27)
					(thickness 0.15)
				)
				(justify left bottom)
				(hide yes)
			)
		)
		(property "Footprint" "antmicro-footprints:F_1206_3216Metric"
			(at 87.63 87.63 0)
			(effects
				(font
					(size 1.27 1.27)
					(thickness 0.15)
				)
				(justify left bottom)
				(hide yes)
			)
		)
		(property "Datasheet" "https://www.littelfuse.com/media?resourcetype=datasheets&itemid=dbe9bcd7-6072-4adf-bf5b-d33e52a6b90f&filename=littelfuse-fuse-466-datasheet"
			(at 87.63 90.17 0)
			(effects
				(font
					(size 1.27 1.27)
					(thickness 0.15)
				)
				(justify left bottom)
				(hide yes)
			)
		)
		(property "Description" ""
			(at 67.31 77.47 0)
			(effects
				(font
					(size 1.27 1.27)
				)
				(hide yes)
			)
		)
		(property "Manufacturer" "Littelfuse"
			(at 87.63 92.71 0)
			(effects
				(font
					(size 1.27 1.27)
					(thickness 0.15)
				)
				(justify left bottom)
				(hide yes)
			)
		)
		(property "MPN" "0466004.NR "
			(at 69.85 76.2 0)
			(effects
				(font
					(size 1.27 1.27)
					(thickness 0.15)
				)
			)
		)
		(property "Author" "Antmicro"
			(at 87.63 97.79 0)
			(effects
				(font
					(size 1.27 1.27)
					(thickness 0.15)
				)
				(justify left bottom)
				(hide yes)
			)
		)
		(property "License" "Apache-2.0"
			(at 87.63 100.33 0)
			(effects
				(font
					(size 1.27 1.27)
					(thickness 0.15)
				)
				(justify left bottom)
				(hide yes)
			)
		)
		(pin "2"
		)
		(pin "1"
		)
		(instances
			(project "data-center-rdimm-ddr5-tester"
				(path ""
					(reference "F2")
					(unit 1)
				)
			)
		)
	)
	(symbol
		(lib_id "antmicropower:GND")
		(at 328.93 33.02 0)
		(unit 1)
		(exclude_from_sim no)
		(in_bom yes)
		(on_board yes)
		(dnp no)
		(fields_autoplaced yes)
		(property "Reference" "#PWR0357"
			(at 328.93 39.37 0)
			(effects
				(font
					(size 1.27 1.27)
				)
				(hide yes)
			)
		)
		(property "Value" "GND"
			(at 327.025 37.465 0)
			(effects
				(font
					(size 1.27 1.27)
					(thickness 0.15)
				)
				(justify left bottom)
			)
		)
		(property "Footprint" ""
			(at 337.82 40.64 0)
			(effects
				(font
					(size 1.27 1.27)
					(thickness 0.15)
				)
				(justify left bottom)
				(hide yes)
			)
		)
		(property "Datasheet" ""
			(at 337.82 45.72 0)
			(effects
				(font
					(size 1.27 1.27)
					(thickness 0.15)
				)
				(justify left bottom)
				(hide yes)
			)
		)
		(property "Description" ""
			(at 328.93 33.02 0)
			(effects
				(font
					(size 1.27 1.27)
				)
				(hide yes)
			)
		)
		(property "Author" "Antmicro"
			(at 337.82 38.1 0)
			(effects
				(font
					(size 1.27 1.27)
					(thickness 0.15)
				)
				(justify left bottom)
				(hide yes)
			)
		)
		(property "License" "Apache-2.0"
			(at 337.82 40.64 0)
			(effects
				(font
					(size 1.27 1.27)
					(thickness 0.15)
				)
				(justify left bottom)
				(hide yes)
			)
		)
		(pin "1"
		)
		(instances
			(project "data-center-rdimm-ddr5-tester"
				(path ""
					(reference "#PWR0357")
					(unit 1)
				)
			)
		)
	)
	(symbol
		(lib_id "antmicropower:+5V")
		(at 328.93 22.86 0)
		(unit 1)
		(exclude_from_sim no)
		(in_bom yes)
		(on_board yes)
		(dnp no)
		(fields_autoplaced yes)
		(property "Reference" "#PWR0324"
			(at 328.93 26.67 0)
			(effects
				(font
					(size 1.27 1.27)
				)
				(hide yes)
			)
		)
		(property "Value" "+5V"
			(at 328.93 19.2856 0)
			(effects
				(font
					(size 1.27 1.27)
					(thickness 0.15)
				)
			)
		)
		(property "Footprint" ""
			(at 344.17 30.48 0)
			(effects
				(font
					(size 1.27 1.27)
					(thickness 0.15)
				)
				(justify left bottom)
				(hide yes)
			)
		)
		(property "Datasheet" ""
			(at 344.17 33.02 0)
			(effects
				(font
					(size 1.27 1.27)
					(thickness 0.15)
				)
				(justify left bottom)
				(hide yes)
			)
		)
		(property "Description" ""
			(at 328.93 22.86 0)
			(effects
				(font
					(size 1.27 1.27)
				)
				(hide yes)
			)
		)
		(property "Author" "Antmicro"
			(at 344.17 30.48 0)
			(effects
				(font
					(size 1.27 1.27)
					(thickness 0.15)
				)
				(justify left bottom)
				(hide yes)
			)
		)
		(property "License" "Apache-2.0"
			(at 344.17 33.02 0)
			(effects
				(font
					(size 1.27 1.27)
					(thickness 0.15)
				)
				(justify left bottom)
				(hide yes)
			)
		)
		(pin "1"
		)
		(instances
			(project "data-center-rdimm-ddr5-tester"
				(path ""
					(reference "#PWR0324")
					(unit 1)
				)
			)
		)
	)
	(symbol
		(lib_id "antmicropower:PWR_FLAG")
		(at 77.47 86.36 0)
		(unit 1)
		(exclude_from_sim no)
		(in_bom yes)
		(on_board yes)
		(dnp no)
		(fields_autoplaced yes)
		(property "Reference" "#FLG0122"
			(at 77.47 84.455 0)
			(effects
				(font
					(size 1.27 1.27)
				)
				(hide yes)
			)
		)
		(property "Value" "PWR_FLAG"
			(at 77.47 82.7842 0)
			(effects
				(font
					(size 1.27 1.27)
				)
			)
		)
		(property "Footprint" ""
			(at 77.47 86.36 0)
			(effects
				(font
					(size 1.27 1.27)
				)
				(hide yes)
			)
		)
		(property "Datasheet" ""
			(at 77.47 86.36 0)
			(effects
				(font
					(size 1.27 1.27)
				)
				(hide yes)
			)
		)
		(property "Description" ""
			(at 77.47 86.36 0)
			(effects
				(font
					(size 1.27 1.27)
				)
				(hide yes)
			)
		)
		(pin "1"
		)
		(instances
			(project "data-center-rdimm-ddr5-tester"
				(path ""
					(reference "#FLG0122")
					(unit 1)
				)
			)
		)
	)
	(symbol
		(lib_id "antmicropower:GND")
		(at 241.3 105.41 0)
		(mirror y)
		(unit 1)
		(exclude_from_sim no)
		(in_bom yes)
		(on_board yes)
		(dnp no)
		(property "Reference" "#PWR0554"
			(at 241.3 111.76 0)
			(effects
				(font
					(size 1.27 1.27)
				)
				(hide yes)
			)
		)
		(property "Value" "GND"
			(at 239.141 109.347 0)
			(effects
				(font
					(size 1.27 1.27)
					(thickness 0.15)
				)
				(justify right)
			)
		)
		(property "Footprint" ""
			(at 232.41 113.03 0)
			(effects
				(font
					(size 1.27 1.27)
					(thickness 0.15)
				)
				(justify left bottom)
				(hide yes)
			)
		)
		(property "Datasheet" ""
			(at 232.41 118.11 0)
			(effects
				(font
					(size 1.27 1.27)
					(thickness 0.15)
				)
				(justify left bottom)
				(hide yes)
			)
		)
		(property "Description" ""
			(at 232.41 120.65 0)
			(effects
				(font
					(size 1.27 1.27)
				)
				(justify left bottom)
				(hide yes)
			)
		)
		(property "Author" "Antmicro"
			(at 232.41 113.03 0)
			(effects
				(font
					(size 1.27 1.27)
					(thickness 0.15)
				)
				(justify left bottom)
				(hide yes)
			)
		)
		(property "License" "Apache-2.0"
			(at 232.41 115.57 0)
			(effects
				(font
					(size 1.27 1.27)
					(thickness 0.15)
				)
				(justify left bottom)
				(hide yes)
			)
		)
		(pin "1"
		)
		(instances
			(project "data-center-rdimm-ddr5-tester"
				(path ""
					(reference "#PWR0554")
					(unit 1)
				)
			)
		)
	)
	(symbol
		(lib_id "antmicroPMICPowerSequencers:LM3880")
		(at 278.13 177.8 0)
		(unit 1)
		(exclude_from_sim no)
		(in_bom yes)
		(on_board yes)
		(dnp no)
		(property "Reference" "U31"
			(at 280.3241 175.26 0)
			(effects
				(font
					(size 1.27 1.27)
					(thickness 0.15)
				)
				(justify left)
			)
		)
		(property "Value" "LM3880"
			(at 303.53 185.42 0)
			(effects
				(font
					(size 1.27 1.27)
					(thickness 0.15)
				)
				(justify left bottom)
				(hide yes)
			)
		)
		(property "Footprint" "antmicro-footprints:SOT-23-6"
			(at 303.53 187.96 0)
			(effects
				(font
					(size 1.27 1.27)
					(thickness 0.15)
				)
				(justify left bottom)
				(hide yes)
			)
		)
		(property "Datasheet" "http://www.ti.com/lit/ds/symlink/lm3880.pdf"
			(at 303.53 190.5 0)
			(effects
				(font
					(size 1.27 1.27)
					(thickness 0.15)
				)
				(justify left bottom)
				(hide yes)
			)
		)
		(property "Description" ""
			(at 278.13 177.8 0)
			(effects
				(font
					(size 1.27 1.27)
				)
				(hide yes)
			)
		)
		(property "Manufacturer" "Texas Instruments"
			(at 303.53 193.04 0)
			(effects
				(font
					(size 1.27 1.27)
					(thickness 0.15)
				)
				(justify left bottom)
				(hide yes)
			)
		)
		(property "MPN" "LM3880MFX-1AA/NOPB"
			(at 279.4 193.04 0)
			(effects
				(font
					(size 1.27 1.27)
					(thickness 0.15)
				)
				(justify left)
			)
		)
		(property "Author" "Antmicro"
			(at 303.53 198.12 0)
			(effects
				(font
					(size 1.27 1.27)
					(thickness 0.15)
				)
				(justify left bottom)
				(hide yes)
			)
		)
		(property "License" "Apache-2.0"
			(at 303.53 200.66 0)
			(effects
				(font
					(size 1.27 1.27)
					(thickness 0.15)
				)
				(justify left bottom)
				(hide yes)
			)
		)
		(pin "4"
		)
		(pin "3"
		)
		(pin "5"
		)
		(pin "1"
		)
		(pin "2"
		)
		(pin "6"
		)
		(instances
			(project "data-center-rdimm-ddr5-tester"
				(path ""
					(reference "U31")
					(unit 1)
				)
			)
		)
	)
	(symbol
		(lib_id "antmicropower:PWR_FLAG")
		(at 135.89 76.2 0)
		(unit 1)
		(exclude_from_sim no)
		(in_bom yes)
		(on_board yes)
		(dnp no)
		(fields_autoplaced yes)
		(property "Reference" "#FLG05"
			(at 135.89 74.295 0)
			(effects
				(font
					(size 1.27 1.27)
				)
				(hide yes)
			)
		)
		(property "Value" "PWR_FLAG"
			(at 135.89 72.6242 0)
			(effects
				(font
					(size 1.27 1.27)
				)
			)
		)
		(property "Footprint" ""
			(at 135.89 76.2 0)
			(effects
				(font
					(size 1.27 1.27)
				)
				(hide yes)
			)
		)
		(property "Datasheet" ""
			(at 135.89 76.2 0)
			(effects
				(font
					(size 1.27 1.27)
				)
				(hide yes)
			)
		)
		(property "Description" ""
			(at 135.89 76.2 0)
			(effects
				(font
					(size 1.27 1.27)
				)
				(hide yes)
			)
		)
		(pin "1"
		)
		(instances
			(project "data-center-rdimm-ddr5-tester"
				(path ""
					(reference "#FLG05")
					(unit 1)
				)
			)
		)
	)
	(symbol
		(lib_id "antmicropower:PWR_FLAG")
		(at 77.47 53.34 0)
		(unit 1)
		(exclude_from_sim no)
		(in_bom yes)
		(on_board yes)
		(dnp no)
		(property "Reference" "#FLG0123"
			(at 77.47 51.435 0)
			(effects
				(font
					(size 1.27 1.27)
				)
				(hide yes)
			)
		)
		(property "Value" "PWR_FLAG"
			(at 77.47 49.7642 0)
			(effects
				(font
					(size 1.27 1.27)
				)
			)
		)
		(property "Footprint" ""
			(at 77.47 53.34 0)
			(effects
				(font
					(size 1.27 1.27)
				)
				(hide yes)
			)
		)
		(property "Datasheet" ""
			(at 77.47 53.34 0)
			(effects
				(font
					(size 1.27 1.27)
				)
				(hide yes)
			)
		)
		(property "Description" ""
			(at 77.47 53.34 0)
			(effects
				(font
					(size 1.27 1.27)
				)
				(hide yes)
			)
		)
		(pin "1"
		)
		(instances
			(project "data-center-rdimm-ddr5-tester"
				(path ""
					(reference "#FLG0123")
					(unit 1)
				)
			)
		)
	)
	(symbol
		(lib_id "antmicropower:GND")
		(at 49.53 58.42 0)
		(unit 1)
		(exclude_from_sim no)
		(in_bom yes)
		(on_board yes)
		(dnp no)
		(fields_autoplaced yes)
		(property "Reference" "#PWR0283"
			(at 49.53 64.77 0)
			(effects
				(font
					(size 1.27 1.27)
				)
				(hide yes)
			)
		)
		(property "Value" "GND"
			(at 47.625 62.865 0)
			(effects
				(font
					(size 1.27 1.27)
					(thickness 0.15)
				)
				(justify left bottom)
			)
		)
		(property "Footprint" ""
			(at 58.42 66.04 0)
			(effects
				(font
					(size 1.27 1.27)
					(thickness 0.15)
				)
				(justify left bottom)
				(hide yes)
			)
		)
		(property "Datasheet" ""
			(at 58.42 71.12 0)
			(effects
				(font
					(size 1.27 1.27)
					(thickness 0.15)
				)
				(justify left bottom)
				(hide yes)
			)
		)
		(property "Description" ""
			(at 49.53 58.42 0)
			(effects
				(font
					(size 1.27 1.27)
				)
				(hide yes)
			)
		)
		(property "Author" "Antmicro"
			(at 58.42 63.5 0)
			(effects
				(font
					(size 1.27 1.27)
					(thickness 0.15)
				)
				(justify left bottom)
				(hide yes)
			)
		)
		(property "License" "Apache-2.0"
			(at 58.42 66.04 0)
			(effects
				(font
					(size 1.27 1.27)
					(thickness 0.15)
				)
				(justify left bottom)
				(hide yes)
			)
		)
		(pin "1"
		)
		(instances
			(project "data-center-rdimm-ddr5-tester"
				(path ""
					(reference "#PWR0283")
					(unit 1)
				)
			)
		)
	)
	(symbol
		(lib_id "antmicropower:GND")
		(at 359.41 104.14 0)
		(unit 1)
		(exclude_from_sim no)
		(in_bom yes)
		(on_board yes)
		(dnp no)
		(fields_autoplaced yes)
		(property "Reference" "#PWR0543"
			(at 359.41 110.49 0)
			(effects
				(font
					(size 1.27 1.27)
				)
				(hide yes)
			)
		)
		(property "Value" "GND"
			(at 357.505 108.585 0)
			(effects
				(font
					(size 1.27 1.27)
					(thickness 0.15)
				)
				(justify left bottom)
			)
		)
		(property "Footprint" ""
			(at 368.3 111.76 0)
			(effects
				(font
					(size 1.27 1.27)
					(thickness 0.15)
				)
				(justify left bottom)
				(hide yes)
			)
		)
		(property "Datasheet" ""
			(at 368.3 116.84 0)
			(effects
				(font
					(size 1.27 1.27)
					(thickness 0.15)
				)
				(justify left bottom)
				(hide yes)
			)
		)
		(property "Description" ""
			(at 359.41 104.14 0)
			(effects
				(font
					(size 1.27 1.27)
				)
				(hide yes)
			)
		)
		(property "Author" "Antmicro"
			(at 368.3 109.22 0)
			(effects
				(font
					(size 1.27 1.27)
					(thickness 0.15)
				)
				(justify left bottom)
				(hide yes)
			)
		)
		(property "License" "Apache-2.0"
			(at 368.3 111.76 0)
			(effects
				(font
					(size 1.27 1.27)
					(thickness 0.15)
				)
				(justify left bottom)
				(hide yes)
			)
		)
		(pin "1"
		)
		(instances
			(project "data-center-rdimm-ddr5-tester"
				(path ""
					(reference "#PWR0543")
					(unit 1)
				)
			)
		)
	)
	(symbol
		(lib_id "antmicroResistors0402:R_47k_0402")
		(at 167.64 194.31 90)
		(unit 1)
		(exclude_from_sim no)
		(in_bom yes)
		(on_board yes)
		(dnp no)
		(property "Reference" "R171"
			(at 166.37 190.5 90)
			(effects
				(font
					(size 1.27 1.27)
				)
				(justify left)
			)
		)
		(property "Value" "R_47k_0402"
			(at 180.34 173.99 0)
			(effects
				(font
					(size 1.27 1.27)
					(thickness 0.15)
				)
				(justify left bottom)
				(hide yes)
			)
		)
		(property "Footprint" "antmicro-footprints:R_0402_1005Metric"
			(at 182.88 173.99 0)
			(effects
				(font
					(size 1.27 1.27)
					(thickness 0.15)
				)
				(justify left bottom)
				(hide yes)
			)
		)
		(property "Datasheet" "https://www.bourns.com/docs/product-datasheets/cr.pdf"
			(at 185.42 173.99 0)
			(effects
				(font
					(size 1.27 1.27)
					(thickness 0.15)
				)
				(justify left bottom)
				(hide yes)
			)
		)
		(property "Description" ""
			(at 167.64 194.31 0)
			(effects
				(font
					(size 1.27 1.27)
				)
				(hide yes)
			)
		)
		(property "Manufacturer" "Bourns"
			(at 190.5 173.99 0)
			(effects
				(font
					(size 1.27 1.27)
					(thickness 0.15)
				)
				(justify left bottom)
				(hide yes)
			)
		)
		(property "MPN" "CR0402-FX-4702GLF"
			(at 187.96 173.99 0)
			(effects
				(font
					(size 1.27 1.27)
					(thickness 0.15)
				)
				(justify left bottom)
				(hide yes)
			)
		)
		(property "Val" "47k"
			(at 166.37 193.04 90)
			(effects
				(font
					(size 1.27 1.27)
					(thickness 0.15)
				)
				(justify left)
			)
		)
		(property "License" "Apache-2.0"
			(at 193.04 173.99 0)
			(effects
				(font
					(size 1.27 1.27)
					(thickness 0.15)
				)
				(justify left bottom)
				(hide yes)
			)
		)
		(property "Author" "Antmicro"
			(at 195.58 173.99 0)
			(effects
				(font
					(size 1.27 1.27)
					(thickness 0.15)
				)
				(justify left bottom)
				(hide yes)
			)
		)
		(property "Tolerance" "1%"
			(at 177.8 173.99 0)
			(effects
				(font
					(size 1.27 1.27)
				)
				(justify left bottom)
				(hide yes)
			)
		)
		(pin "1"
		)
		(pin "2"
		)
		(instances
			(project "data-center-rdimm-ddr5-tester"
				(path ""
					(reference "R171")
					(unit 1)
				)
			)
		)
	)
	(symbol
		(lib_id "antmicropower:+12V")
		(at 53.34 76.2 0)
		(unit 1)
		(exclude_from_sim no)
		(in_bom yes)
		(on_board yes)
		(dnp no)
		(fields_autoplaced yes)
		(property "Reference" "#PWR0421"
			(at 53.34 80.01 0)
			(effects
				(font
					(size 1.27 1.27)
				)
				(hide yes)
			)
		)
		(property "Value" "+12V"
			(at 53.34 72.6242 0)
			(effects
				(font
					(size 1.27 1.27)
				)
			)
		)
		(property "Footprint" ""
			(at 53.34 76.2 0)
			(effects
				(font
					(size 1.27 1.27)
				)
				(hide yes)
			)
		)
		(property "Datasheet" ""
			(at 53.34 76.2 0)
			(effects
				(font
					(size 1.27 1.27)
				)
				(hide yes)
			)
		)
		(property "Description" ""
			(at 53.34 76.2 0)
			(effects
				(font
					(size 1.27 1.27)
				)
				(hide yes)
			)
		)
		(pin "1"
		)
		(instances
			(project "data-center-rdimm-ddr5-tester"
				(path ""
					(reference "#PWR0421")
					(unit 1)
				)
			)
		)
	)
	(symbol
		(lib_id "antmicroCapacitors0603:C_10u_25V_0603")
		(at 307.34 86.36 90)
		(unit 1)
		(exclude_from_sim no)
		(in_bom yes)
		(on_board yes)
		(dnp no)
		(fields_autoplaced yes)
		(property "Reference" "C327"
			(at 309.88 82.5436 90)
			(effects
				(font
					(size 1.27 1.27)
					(thickness 0.15)
				)
				(justify right)
			)
		)
		(property "Value" "C_10u_25V_0603"
			(at 317.5 66.04 0)
			(effects
				(font
					(size 1.27 1.27)
					(thickness 0.15)
				)
				(justify left bottom)
				(hide yes)
			)
		)
		(property "Footprint" "antmicro-footprints:C_0603_1608Metric"
			(at 320.04 66.04 0)
			(effects
				(font
					(size 1.27 1.27)
					(thickness 0.15)
				)
				(justify left bottom)
				(hide yes)
			)
		)
		(property "Datasheet" "https://product.tdk.com/en/search/capacitor/ceramic/mlcc/info?part_no=C1608X5R1E106M080AC"
			(at 322.58 66.04 0)
			(effects
				(font
					(size 1.27 1.27)
					(thickness 0.15)
				)
				(justify left bottom)
				(hide yes)
			)
		)
		(property "Description" ""
			(at 307.34 86.36 0)
			(effects
				(font
					(size 1.27 1.27)
				)
				(hide yes)
			)
		)
		(property "MPN" "C1608X5R1E106M080AC"
			(at 325.12 66.04 0)
			(effects
				(font
					(size 1.27 1.27)
					(thickness 0.15)
				)
				(justify left bottom)
				(hide yes)
			)
		)
		(property "Manufacturer" "TDK"
			(at 327.66 66.04 0)
			(effects
				(font
					(size 1.27 1.27)
					(thickness 0.15)
				)
				(justify left bottom)
				(hide yes)
			)
		)
		(property "License" "Apache-2.0"
			(at 330.2 66.04 0)
			(effects
				(font
					(size 1.27 1.27)
					(thickness 0.15)
				)
				(justify left bottom)
				(hide yes)
			)
		)
		(property "Author" "Antmicro"
			(at 332.74 66.04 0)
			(effects
				(font
					(size 1.27 1.27)
					(thickness 0.15)
				)
				(justify left bottom)
				(hide yes)
			)
		)
		(property "Val" "10u"
			(at 309.88 85.0836 90)
			(effects
				(font
					(size 1.27 1.27)
					(thickness 0.15)
				)
				(justify right)
			)
		)
		(property "Voltage" "25V"
			(at 335.28 66.04 0)
			(effects
				(font
					(size 1.27 1.27)
				)
				(justify left bottom)
				(hide yes)
			)
		)
		(property "Dielectric" ""
			(at 337.82 66.04 0)
			(effects
				(font
					(size 1.27 1.27)
				)
				(justify left bottom)
				(hide yes)
			)
		)
		(pin "2"
		)
		(pin "1"
		)
		(instances
			(project "data-center-rdimm-ddr5-tester"
				(path ""
					(reference "C327")
					(unit 1)
				)
			)
		)
	)
	(symbol
		(lib_id "antmicroResistors0402:R_47k_0402")
		(at 325.12 105.41 90)
		(unit 1)
		(exclude_from_sim no)
		(in_bom yes)
		(on_board yes)
		(dnp no)
		(fields_autoplaced yes)
		(property "Reference" "R250"
			(at 327.66 101.6 90)
			(effects
				(font
					(size 1.27 1.27)
					(thickness 0.15)
				)
				(justify right)
			)
		)
		(property "Value" "R_47k_0402"
			(at 337.82 85.09 0)
			(effects
				(font
					(size 1.27 1.27)
					(thickness 0.15)
				)
				(justify left bottom)
				(hide yes)
			)
		)
		(property "Footprint" "antmicro-footprints:R_0402_1005Metric"
			(at 340.36 85.09 0)
			(effects
				(font
					(size 1.27 1.27)
					(thickness 0.15)
				)
				(justify left bottom)
				(hide yes)
			)
		)
		(property "Datasheet" "https://www.bourns.com/docs/product-datasheets/cr.pdf"
			(at 342.9 85.09 0)
			(effects
				(font
					(size 1.27 1.27)
					(thickness 0.15)
				)
				(justify left bottom)
				(hide yes)
			)
		)
		(property "Description" ""
			(at 325.12 105.41 0)
			(effects
				(font
					(size 1.27 1.27)
				)
				(hide yes)
			)
		)
		(property "MPN" "CR0402-FX-4702GLF"
			(at 345.44 85.09 0)
			(effects
				(font
					(size 1.27 1.27)
					(thickness 0.15)
				)
				(justify left bottom)
				(hide yes)
			)
		)
		(property "Manufacturer" "Bourns"
			(at 347.98 85.09 0)
			(effects
				(font
					(size 1.27 1.27)
					(thickness 0.15)
				)
				(justify left bottom)
				(hide yes)
			)
		)
		(property "License" "Apache-2.0"
			(at 350.52 85.09 0)
			(effects
				(font
					(size 1.27 1.27)
					(thickness 0.15)
				)
				(justify left bottom)
				(hide yes)
			)
		)
		(property "Author" "Antmicro"
			(at 353.06 85.09 0)
			(effects
				(font
					(size 1.27 1.27)
					(thickness 0.15)
				)
				(justify left bottom)
				(hide yes)
			)
		)
		(property "Val" "47k"
			(at 327.66 104.14 90)
			(effects
				(font
					(size 1.27 1.27)
					(thickness 0.15)
				)
				(justify right)
			)
		)
		(property "Tolerance" "1%"
			(at 335.28 85.09 0)
			(effects
				(font
					(size 1.27 1.27)
				)
				(justify left bottom)
				(hide yes)
			)
		)
		(pin "2"
		)
		(pin "1"
		)
		(instances
			(project "data-center-rdimm-ddr5-tester"
				(path ""
					(reference "R250")
					(unit 1)
				)
			)
		)
	)
	(symbol
		(lib_id "antmicroCapacitors0603:C_10u_25V_0603")
		(at 370.84 102.87 90)
		(unit 1)
		(exclude_from_sim no)
		(in_bom yes)
		(on_board yes)
		(dnp no)
		(fields_autoplaced yes)
		(property "Reference" "C323"
			(at 373.38 99.0536 90)
			(effects
				(font
					(size 1.27 1.27)
					(thickness 0.15)
				)
				(justify right)
			)
		)
		(property "Value" "C_10u_25V_0603"
			(at 381 82.55 0)
			(effects
				(font
					(size 1.27 1.27)
					(thickness 0.15)
				)
				(justify left bottom)
				(hide yes)
			)
		)
		(property "Footprint" "antmicro-footprints:C_0603_1608Metric"
			(at 383.54 82.55 0)
			(effects
				(font
					(size 1.27 1.27)
					(thickness 0.15)
				)
				(justify left bottom)
				(hide yes)
			)
		)
		(property "Datasheet" "https://product.tdk.com/en/search/capacitor/ceramic/mlcc/info?part_no=C1608X5R1E106M080AC"
			(at 386.08 82.55 0)
			(effects
				(font
					(size 1.27 1.27)
					(thickness 0.15)
				)
				(justify left bottom)
				(hide yes)
			)
		)
		(property "Description" ""
			(at 370.84 102.87 0)
			(effects
				(font
					(size 1.27 1.27)
				)
				(hide yes)
			)
		)
		(property "MPN" "C1608X5R1E106M080AC"
			(at 388.62 82.55 0)
			(effects
				(font
					(size 1.27 1.27)
					(thickness 0.15)
				)
				(justify left bottom)
				(hide yes)
			)
		)
		(property "Manufacturer" "TDK"
			(at 391.16 82.55 0)
			(effects
				(font
					(size 1.27 1.27)
					(thickness 0.15)
				)
				(justify left bottom)
				(hide yes)
			)
		)
		(property "License" "Apache-2.0"
			(at 393.7 82.55 0)
			(effects
				(font
					(size 1.27 1.27)
					(thickness 0.15)
				)
				(justify left bottom)
				(hide yes)
			)
		)
		(property "Author" "Antmicro"
			(at 396.24 82.55 0)
			(effects
				(font
					(size 1.27 1.27)
					(thickness 0.15)
				)
				(justify left bottom)
				(hide yes)
			)
		)
		(property "Val" "10u"
			(at 373.38 101.5936 90)
			(effects
				(font
					(size 1.27 1.27)
					(thickness 0.15)
				)
				(justify right)
			)
		)
		(property "Voltage" "25V"
			(at 398.78 82.55 0)
			(effects
				(font
					(size 1.27 1.27)
				)
				(justify left bottom)
				(hide yes)
			)
		)
		(property "Dielectric" ""
			(at 401.32 82.55 0)
			(effects
				(font
					(size 1.27 1.27)
				)
				(justify left bottom)
				(hide yes)
			)
		)
		(pin "2"
		)
		(pin "1"
		)
		(instances
			(project "data-center-rdimm-ddr5-tester"
				(path ""
					(reference "C323")
					(unit 1)
				)
			)
		)
	)
	(symbol
		(lib_id "antmicroCapacitors0402:C_1u_0402")
		(at 238.76 45.72 90)
		(unit 1)
		(exclude_from_sim no)
		(in_bom yes)
		(on_board yes)
		(dnp no)
		(property "Reference" "C194"
			(at 239.395 41.275 90)
			(effects
				(font
					(size 1.27 1.27)
				)
				(justify right)
			)
		)
		(property "Value" "C_1u_0402"
			(at 248.92 25.4 0)
			(effects
				(font
					(size 1.27 1.27)
					(thickness 0.15)
				)
				(justify left bottom)
				(hide yes)
			)
		)
		(property "Footprint" "antmicro-footprints:C_0402_1005Metric"
			(at 251.46 25.4 0)
			(effects
				(font
					(size 1.27 1.27)
					(thickness 0.15)
				)
				(justify left bottom)
				(hide yes)
			)
		)
		(property "Datasheet" "https://product.tdk.com/en/search/capacitor/ceramic/mlcc/info?part_no=C1005X6S1A105K050BC"
			(at 254 25.4 0)
			(effects
				(font
					(size 1.27 1.27)
					(thickness 0.15)
				)
				(justify left bottom)
				(hide yes)
			)
		)
		(property "Description" ""
			(at 238.76 45.72 0)
			(effects
				(font
					(size 1.27 1.27)
				)
				(hide yes)
			)
		)
		(property "Manufacturer" "TDK"
			(at 259.08 25.4 0)
			(effects
				(font
					(size 1.27 1.27)
					(thickness 0.15)
				)
				(justify left bottom)
				(hide yes)
			)
		)
		(property "MPN" "C1005X6S1A105K050BC"
			(at 256.54 25.4 0)
			(effects
				(font
					(size 1.27 1.27)
					(thickness 0.15)
				)
				(justify left bottom)
				(hide yes)
			)
		)
		(property "Val" "1u"
			(at 239.395 45.085 90)
			(effects
				(font
					(size 1.27 1.27)
					(thickness 0.15)
				)
				(justify right)
			)
		)
		(property "License" "Apache-2.0"
			(at 261.62 25.4 0)
			(effects
				(font
					(size 1.27 1.27)
					(thickness 0.15)
				)
				(justify left bottom)
				(hide yes)
			)
		)
		(property "Author" "Antmicro"
			(at 264.16 25.4 0)
			(effects
				(font
					(size 1.27 1.27)
					(thickness 0.15)
				)
				(justify left bottom)
				(hide yes)
			)
		)
		(property "Voltage" ""
			(at 266.7 25.4 0)
			(effects
				(font
					(size 1.27 1.27)
				)
				(justify left bottom)
				(hide yes)
			)
		)
		(property "Dielectric" ""
			(at 269.24 25.4 0)
			(effects
				(font
					(size 1.27 1.27)
				)
				(justify left bottom)
				(hide yes)
			)
		)
		(pin "1"
		)
		(pin "2"
		)
		(instances
			(project "data-center-rdimm-ddr5-tester"
				(path ""
					(reference "C194")
					(unit 1)
				)
			)
		)
	)
	(symbol
		(lib_id "antmicroPMICORControllersIdealDiodes:LTC4412IS6")
		(at 87.63 54.61 0)
		(unit 1)
		(exclude_from_sim no)
		(in_bom yes)
		(on_board yes)
		(dnp no)
		(fields_autoplaced yes)
		(property "Reference" "U17"
			(at 96.52 46.99 0)
			(effects
				(font
					(size 1.27 1.27)
					(thickness 0.15)
				)
			)
		)
		(property "Value" "LTC4412IS6"
			(at 119.38 59.69 0)
			(effects
				(font
					(size 1.27 1.27)
					(thickness 0.15)
				)
				(justify left bottom)
				(hide yes)
			)
		)
		(property "Footprint" "antmicro-footprints:SOT-23-6"
			(at 119.38 62.23 0)
			(effects
				(font
					(size 1.27 1.27)
					(thickness 0.15)
				)
				(justify left bottom)
				(hide yes)
			)
		)
		(property "Datasheet" "https://www.mouser.com/datasheet/2/308/NCV8187_D-1813214.pdf"
			(at 119.38 64.77 0)
			(effects
				(font
					(size 1.27 1.27)
					(thickness 0.15)
				)
				(justify left bottom)
				(hide yes)
			)
		)
		(property "Description" ""
			(at 87.63 54.61 0)
			(effects
				(font
					(size 1.27 1.27)
				)
				(hide yes)
			)
		)
		(property "MPN" "LTC4412IS6#TRMPBF"
			(at 96.52 49.53 0)
			(effects
				(font
					(size 1.27 1.27)
					(thickness 0.15)
				)
			)
		)
		(property "Manufacturer" "Analog Devices"
			(at 119.38 69.85 0)
			(effects
				(font
					(size 1.27 1.27)
					(thickness 0.15)
				)
				(justify left bottom)
				(hide yes)
			)
		)
		(property "Author" "Antmicro"
			(at 119.38 72.39 0)
			(effects
				(font
					(size 1.27 1.27)
					(thickness 0.15)
				)
				(justify left bottom)
				(hide yes)
			)
		)
		(property "License" "Apache-2.0"
			(at 119.38 74.93 0)
			(effects
				(font
					(size 1.27 1.27)
					(thickness 0.15)
				)
				(justify left bottom)
				(hide yes)
			)
		)
		(pin "2"
		)
		(pin "3"
		)
		(pin "5"
		)
		(pin "1"
		)
		(pin "6"
		)
		(pin "4"
		)
		(instances
			(project "data-center-rdimm-ddr5-tester"
				(path ""
					(reference "U17")
					(unit 1)
				)
			)
		)
	)
	(symbol
		(lib_id "antmicroBarrelPowerConnectors:BarrelJack_Pin2mm_694106106102")
		(at 43.18 44.45 0)
		(unit 1)
		(exclude_from_sim no)
		(in_bom yes)
		(on_board yes)
		(dnp no)
		(fields_autoplaced yes)
		(property "Reference" "J7"
			(at 35.56 38.1 0)
			(effects
				(font
					(size 1.27 1.27)
					(thickness 0.15)
				)
			)
		)
		(property "Value" "BarrelJack_Pin2mm_694106106102"
			(at 58.42 54.61 0)
			(effects
				(font
					(size 1.27 1.27)
					(thickness 0.15)
				)
				(justify left bottom)
				(hide yes)
			)
		)
		(property "Footprint" "antmicro-footprints:BarrelJack_Pin2mm_694106106102"
			(at 58.42 57.15 0)
			(effects
				(font
					(size 1.27 1.27)
					(thickness 0.15)
				)
				(justify left bottom)
				(hide yes)
			)
		)
		(property "Datasheet" "https://www.we-online.com/components/products/datasheet/694106106102.pdf"
			(at 58.42 59.69 0)
			(effects
				(font
					(size 1.27 1.27)
					(thickness 0.15)
				)
				(justify left bottom)
				(hide yes)
			)
		)
		(property "Description" "DC Power Connector, Jack, 5 A, 2 mm, PCB Mount, Surface Mount"
			(at 58.42 62.23 0)
			(effects
				(font
					(size 1.27 1.27)
					(thickness 0.15)
				)
				(justify left bottom)
				(hide yes)
			)
		)
		(property "MPN" "694106106102"
			(at 35.56 40.64 0)
			(effects
				(font
					(size 1.27 1.27)
					(thickness 0.15)
				)
			)
		)
		(property "Manufacturer" "Würth Elektronik"
			(at 58.42 64.77 0)
			(effects
				(font
					(size 1.27 1.27)
					(thickness 0.15)
				)
				(justify left bottom)
				(hide yes)
			)
		)
		(property "Author" "Antmicro"
			(at 58.42 67.31 0)
			(effects
				(font
					(size 1.27 1.27)
					(thickness 0.15)
				)
				(justify left bottom)
				(hide yes)
			)
		)
		(property "License" "Apache-2.0"
			(at 58.42 69.85 0)
			(effects
				(font
					(size 1.27 1.27)
					(thickness 0.15)
				)
				(justify left bottom)
				(hide yes)
			)
		)
		(pin "2"
		)
		(pin "3"
		)
		(pin "1"
		)
		(pin "1"
		)
		(instances
			(project "data-center-rdimm-ddr5-tester"
				(path ""
					(reference "J7")
					(unit 1)
				)
			)
		)
	)
	(symbol
		(lib_id "antmicroResistors0402:R_4k7_0402")
		(at 229.87 175.26 90)
		(unit 1)
		(exclude_from_sim no)
		(in_bom yes)
		(on_board yes)
		(dnp no)
		(fields_autoplaced yes)
		(property "Reference" "R206"
			(at 232.41 171.45 90)
			(effects
				(font
					(size 1.27 1.27)
					(thickness 0.15)
				)
				(justify right)
			)
		)
		(property "Value" "R_4k7_0402"
			(at 242.57 154.94 0)
			(effects
				(font
					(size 1.27 1.27)
					(thickness 0.15)
				)
				(justify left bottom)
				(hide yes)
			)
		)
		(property "Footprint" "antmicro-footprints:R_0402_1005Metric"
			(at 245.11 154.94 0)
			(effects
				(font
					(size 1.27 1.27)
					(thickness 0.15)
				)
				(justify left bottom)
				(hide yes)
			)
		)
		(property "Datasheet" "https://www.bourns.com/docs/product-datasheets/cr.pdf"
			(at 247.65 154.94 0)
			(effects
				(font
					(size 1.27 1.27)
					(thickness 0.15)
				)
				(justify left bottom)
				(hide yes)
			)
		)
		(property "Description" ""
			(at 229.87 175.26 0)
			(effects
				(font
					(size 1.27 1.27)
				)
				(hide yes)
			)
		)
		(property "MPN" "CR0402-FX-4701GLF"
			(at 250.19 154.94 0)
			(effects
				(font
					(size 1.27 1.27)
					(thickness 0.15)
				)
				(justify left bottom)
				(hide yes)
			)
		)
		(property "Manufacturer" "Bourns"
			(at 252.73 154.94 0)
			(effects
				(font
					(size 1.27 1.27)
					(thickness 0.15)
				)
				(justify left bottom)
				(hide yes)
			)
		)
		(property "License" "Apache-2.0"
			(at 255.27 154.94 0)
			(effects
				(font
					(size 1.27 1.27)
					(thickness 0.15)
				)
				(justify left bottom)
				(hide yes)
			)
		)
		(property "Author" "Antmicro"
			(at 257.81 154.94 0)
			(effects
				(font
					(size 1.27 1.27)
					(thickness 0.15)
				)
				(justify left bottom)
				(hide yes)
			)
		)
		(property "Val" "4k7"
			(at 232.41 173.99 90)
			(effects
				(font
					(size 1.27 1.27)
					(thickness 0.15)
				)
				(justify right)
			)
		)
		(property "Tolerance" "1%"
			(at 240.03 154.94 0)
			(effects
				(font
					(size 1.27 1.27)
				)
				(justify left bottom)
				(hide yes)
			)
		)
		(pin "2"
		)
		(pin "1"
		)
		(instances
			(project "data-center-rdimm-ddr5-tester"
				(path ""
					(reference "R206")
					(unit 1)
				)
			)
		)
	)
	(symbol
		(lib_id "antmicroResistors0402:R_47k_0402")
		(at 180.34 175.26 90)
		(unit 1)
		(exclude_from_sim no)
		(in_bom yes)
		(on_board yes)
		(dnp no)
		(property "Reference" "R172"
			(at 179.07 171.45 90)
			(effects
				(font
					(size 1.27 1.27)
				)
				(justify left)
			)
		)
		(property "Value" "R_47k_0402"
			(at 193.04 154.94 0)
			(effects
				(font
					(size 1.27 1.27)
					(thickness 0.15)
				)
				(justify left bottom)
				(hide yes)
			)
		)
		(property "Footprint" "antmicro-footprints:R_0402_1005Metric"
			(at 195.58 154.94 0)
			(effects
				(font
					(size 1.27 1.27)
					(thickness 0.15)
				)
				(justify left bottom)
				(hide yes)
			)
		)
		(property "Datasheet" "https://www.bourns.com/docs/product-datasheets/cr.pdf"
			(at 198.12 154.94 0)
			(effects
				(font
					(size 1.27 1.27)
					(thickness 0.15)
				)
				(justify left bottom)
				(hide yes)
			)
		)
		(property "Description" ""
			(at 180.34 175.26 0)
			(effects
				(font
					(size 1.27 1.27)
				)
				(hide yes)
			)
		)
		(property "Manufacturer" "Bourns"
			(at 203.2 154.94 0)
			(effects
				(font
					(size 1.27 1.27)
					(thickness 0.15)
				)
				(justify left bottom)
				(hide yes)
			)
		)
		(property "MPN" "CR0402-FX-4702GLF"
			(at 200.66 154.94 0)
			(effects
				(font
					(size 1.27 1.27)
					(thickness 0.15)
				)
				(justify left bottom)
				(hide yes)
			)
		)
		(property "Val" "47k"
			(at 179.07 173.99 90)
			(effects
				(font
					(size 1.27 1.27)
					(thickness 0.15)
				)
				(justify left)
			)
		)
		(property "License" "Apache-2.0"
			(at 205.74 154.94 0)
			(effects
				(font
					(size 1.27 1.27)
					(thickness 0.15)
				)
				(justify left bottom)
				(hide yes)
			)
		)
		(property "Author" "Antmicro"
			(at 208.28 154.94 0)
			(effects
				(font
					(size 1.27 1.27)
					(thickness 0.15)
				)
				(justify left bottom)
				(hide yes)
			)
		)
		(property "Tolerance" "1%"
			(at 190.5 154.94 0)
			(effects
				(font
					(size 1.27 1.27)
				)
				(justify left bottom)
				(hide yes)
			)
		)
		(pin "1"
		)
		(pin "2"
		)
		(instances
			(project "data-center-rdimm-ddr5-tester"
				(path ""
					(reference "R172")
					(unit 1)
				)
			)
		)
	)
	(symbol
		(lib_id "antmicropower:GND")
		(at 93.98 142.24 0)
		(unit 1)
		(exclude_from_sim no)
		(in_bom yes)
		(on_board yes)
		(dnp no)
		(property "Reference" "#PWR0330"
			(at 93.98 148.59 0)
			(effects
				(font
					(size 1.27 1.27)
				)
				(hide yes)
			)
		)
		(property "Value" "GND"
			(at 92.075 146.685 0)
			(effects
				(font
					(size 1.27 1.27)
					(thickness 0.15)
				)
				(justify left bottom)
			)
		)
		(property "Footprint" ""
			(at 102.87 149.86 0)
			(effects
				(font
					(size 1.27 1.27)
					(thickness 0.15)
				)
				(justify left bottom)
				(hide yes)
			)
		)
		(property "Datasheet" ""
			(at 102.87 154.94 0)
			(effects
				(font
					(size 1.27 1.27)
					(thickness 0.15)
				)
				(justify left bottom)
				(hide yes)
			)
		)
		(property "Description" ""
			(at 93.98 142.24 0)
			(effects
				(font
					(size 1.27 1.27)
				)
				(hide yes)
			)
		)
		(property "Author" "Antmicro"
			(at 102.87 147.32 0)
			(effects
				(font
					(size 1.27 1.27)
					(thickness 0.15)
				)
				(justify left bottom)
				(hide yes)
			)
		)
		(property "License" "Apache-2.0"
			(at 102.87 149.86 0)
			(effects
				(font
					(size 1.27 1.27)
					(thickness 0.15)
				)
				(justify left bottom)
				(hide yes)
			)
		)
		(pin "1"
		)
		(instances
			(project "data-center-rdimm-ddr5-tester"
				(path ""
					(reference "#PWR0330")
					(unit 1)
				)
			)
		)
	)
	(symbol
		(lib_id "antmicropower:GND")
		(at 185.42 96.52 0)
		(mirror y)
		(unit 1)
		(exclude_from_sim no)
		(in_bom yes)
		(on_board yes)
		(dnp no)
		(property "Reference" "#PWR0550"
			(at 185.42 102.87 0)
			(effects
				(font
					(size 1.27 1.27)
				)
				(hide yes)
			)
		)
		(property "Value" "GND"
			(at 185.42 100.076 0)
			(effects
				(font
					(size 1.27 1.27)
					(thickness 0.15)
				)
			)
		)
		(property "Footprint" ""
			(at 176.53 104.14 0)
			(effects
				(font
					(size 1.27 1.27)
					(thickness 0.15)
				)
				(justify left bottom)
				(hide yes)
			)
		)
		(property "Datasheet" ""
			(at 176.53 109.22 0)
			(effects
				(font
					(size 1.27 1.27)
					(thickness 0.15)
				)
				(justify left bottom)
				(hide yes)
			)
		)
		(property "Description" ""
			(at 176.53 111.76 0)
			(effects
				(font
					(size 1.27 1.27)
				)
				(justify left bottom)
				(hide yes)
			)
		)
		(property "Author" "Antmicro"
			(at 176.53 104.14 0)
			(effects
				(font
					(size 1.27 1.27)
					(thickness 0.15)
				)
				(justify left bottom)
				(hide yes)
			)
		)
		(property "License" "Apache-2.0"
			(at 176.53 106.68 0)
			(effects
				(font
					(size 1.27 1.27)
					(thickness 0.15)
				)
				(justify left bottom)
				(hide yes)
			)
		)
		(pin "1"
		)
		(instances
			(project "data-center-rdimm-ddr5-tester"
				(path ""
					(reference "#PWR0550")
					(unit 1)
				)
			)
		)
	)
	(symbol
		(lib_id "antmicropower:GND")
		(at 278.13 194.31 0)
		(unit 1)
		(exclude_from_sim no)
		(in_bom yes)
		(on_board yes)
		(dnp no)
		(fields_autoplaced yes)
		(property "Reference" "#PWR0389"
			(at 278.13 200.66 0)
			(effects
				(font
					(size 1.27 1.27)
				)
				(hide yes)
			)
		)
		(property "Value" "GND"
			(at 276.225 198.755 0)
			(effects
				(font
					(size 1.27 1.27)
					(thickness 0.15)
				)
				(justify left bottom)
			)
		)
		(property "Footprint" ""
			(at 287.02 201.93 0)
			(effects
				(font
					(size 1.27 1.27)
					(thickness 0.15)
				)
				(justify left bottom)
				(hide yes)
			)
		)
		(property "Datasheet" ""
			(at 287.02 207.01 0)
			(effects
				(font
					(size 1.27 1.27)
					(thickness 0.15)
				)
				(justify left bottom)
				(hide yes)
			)
		)
		(property "Description" ""
			(at 278.13 194.31 0)
			(effects
				(font
					(size 1.27 1.27)
				)
				(hide yes)
			)
		)
		(property "Author" "Antmicro"
			(at 287.02 199.39 0)
			(effects
				(font
					(size 1.27 1.27)
					(thickness 0.15)
				)
				(justify left bottom)
				(hide yes)
			)
		)
		(property "License" "Apache-2.0"
			(at 287.02 201.93 0)
			(effects
				(font
					(size 1.27 1.27)
					(thickness 0.15)
				)
				(justify left bottom)
				(hide yes)
			)
		)
		(pin "1"
		)
		(instances
			(project "data-center-rdimm-ddr5-tester"
				(path ""
					(reference "#PWR0389")
					(unit 1)
				)
			)
		)
	)
	(symbol
		(lib_id "antmicropower:GND")
		(at 247.65 269.24 0)
		(unit 1)
		(exclude_from_sim no)
		(in_bom yes)
		(on_board yes)
		(dnp no)
		(fields_autoplaced yes)
		(property "Reference" "#PWR0391"
			(at 247.65 275.59 0)
			(effects
				(font
					(size 1.27 1.27)
				)
				(hide yes)
			)
		)
		(property "Value" "GND"
			(at 245.745 273.685 0)
			(effects
				(font
					(size 1.27 1.27)
					(thickness 0.15)
				)
				(justify left bottom)
			)
		)
		(property "Footprint" ""
			(at 256.54 276.86 0)
			(effects
				(font
					(size 1.27 1.27)
					(thickness 0.15)
				)
				(justify left bottom)
				(hide yes)
			)
		)
		(property "Datasheet" ""
			(at 256.54 281.94 0)
			(effects
				(font
					(size 1.27 1.27)
					(thickness 0.15)
				)
				(justify left bottom)
				(hide yes)
			)
		)
		(property "Description" ""
			(at 247.65 269.24 0)
			(effects
				(font
					(size 1.27 1.27)
				)
				(hide yes)
			)
		)
		(property "Author" "Antmicro"
			(at 256.54 274.32 0)
			(effects
				(font
					(size 1.27 1.27)
					(thickness 0.15)
				)
				(justify left bottom)
				(hide yes)
			)
		)
		(property "License" "Apache-2.0"
			(at 256.54 276.86 0)
			(effects
				(font
					(size 1.27 1.27)
					(thickness 0.15)
				)
				(justify left bottom)
				(hide yes)
			)
		)
		(pin "1"
		)
		(instances
			(project "data-center-rdimm-ddr5-tester"
				(path ""
					(reference "#PWR0391")
					(unit 1)
				)
			)
		)
	)
	(symbol
		(lib_id "antmicropower:+3V3_AON")
		(at 262.89 166.37 0)
		(unit 1)
		(exclude_from_sim no)
		(in_bom yes)
		(on_board yes)
		(dnp no)
		(fields_autoplaced yes)
		(property "Reference" "#PWR0382"
			(at 262.89 170.18 0)
			(effects
				(font
					(size 1.27 1.27)
				)
				(hide yes)
			)
		)
		(property "Value" "+3V3_AON"
			(at 262.89 160.655 0)
			(effects
				(font
					(size 1.27 1.27)
				)
			)
		)
		(property "Footprint" ""
			(at 262.89 166.37 0)
			(effects
				(font
					(size 1.27 1.27)
				)
				(hide yes)
			)
		)
		(property "Datasheet" ""
			(at 262.89 166.37 0)
			(effects
				(font
					(size 1.27 1.27)
				)
				(hide yes)
			)
		)
		(property "Description" ""
			(at 262.89 166.37 0)
			(effects
				(font
					(size 1.27 1.27)
				)
				(hide yes)
			)
		)
		(pin "1"
		)
		(instances
			(project "data-center-rdimm-ddr5-tester"
				(path ""
					(reference "#PWR0382")
					(unit 1)
				)
			)
		)
	)
	(symbol
		(lib_id "antmicropower:+3V3_AON")
		(at 180.34 166.37 0)
		(unit 1)
		(exclude_from_sim no)
		(in_bom yes)
		(on_board yes)
		(dnp no)
		(property "Reference" "#PWR0358"
			(at 180.34 170.18 0)
			(effects
				(font
					(size 1.27 1.27)
				)
				(hide yes)
			)
		)
		(property "Value" "+3V3_AON"
			(at 180.34 162.56 0)
			(effects
				(font
					(size 1.27 1.27)
				)
			)
		)
		(property "Footprint" ""
			(at 180.34 166.37 0)
			(effects
				(font
					(size 1.27 1.27)
				)
				(hide yes)
			)
		)
		(property "Datasheet" ""
			(at 180.34 166.37 0)
			(effects
				(font
					(size 1.27 1.27)
				)
				(hide yes)
			)
		)
		(property "Description" ""
			(at 180.34 166.37 0)
			(effects
				(font
					(size 1.27 1.27)
				)
				(hide yes)
			)
		)
		(pin "1"
		)
		(instances
			(project "data-center-rdimm-ddr5-tester"
				(path ""
					(reference "#PWR0358")
					(unit 1)
				)
			)
		)
	)
	(symbol
		(lib_id "antmicroResistors0402:R_47k_0402")
		(at 299.72 179.07 90)
		(unit 1)
		(exclude_from_sim no)
		(in_bom yes)
		(on_board yes)
		(dnp no)
		(property "Reference" "R187"
			(at 300.99 175.26 90)
			(effects
				(font
					(size 1.27 1.27)
				)
				(justify right)
			)
		)
		(property "Value" "R_47k_0402"
			(at 312.42 158.75 0)
			(effects
				(font
					(size 1.27 1.27)
					(thickness 0.15)
				)
				(justify left bottom)
				(hide yes)
			)
		)
		(property "Footprint" "antmicro-footprints:R_0402_1005Metric"
			(at 314.96 158.75 0)
			(effects
				(font
					(size 1.27 1.27)
					(thickness 0.15)
				)
				(justify left bottom)
				(hide yes)
			)
		)
		(property "Datasheet" "https://www.bourns.com/docs/product-datasheets/cr.pdf"
			(at 317.5 158.75 0)
			(effects
				(font
					(size 1.27 1.27)
					(thickness 0.15)
				)
				(justify left bottom)
				(hide yes)
			)
		)
		(property "Description" ""
			(at 299.72 179.07 0)
			(effects
				(font
					(size 1.27 1.27)
				)
				(hide yes)
			)
		)
		(property "Manufacturer" "Bourns"
			(at 322.58 158.75 0)
			(effects
				(font
					(size 1.27 1.27)
					(thickness 0.15)
				)
				(justify left bottom)
				(hide yes)
			)
		)
		(property "MPN" "CR0402-FX-4702GLF"
			(at 320.04 158.75 0)
			(effects
				(font
					(size 1.27 1.27)
					(thickness 0.15)
				)
				(justify left bottom)
				(hide yes)
			)
		)
		(property "Val" "47k"
			(at 300.99 177.8 90)
			(effects
				(font
					(size 1.27 1.27)
					(thickness 0.15)
				)
				(justify right)
			)
		)
		(property "License" "Apache-2.0"
			(at 325.12 158.75 0)
			(effects
				(font
					(size 1.27 1.27)
					(thickness 0.15)
				)
				(justify left bottom)
				(hide yes)
			)
		)
		(property "Author" "Antmicro"
			(at 327.66 158.75 0)
			(effects
				(font
					(size 1.27 1.27)
					(thickness 0.15)
				)
				(justify left bottom)
				(hide yes)
			)
		)
		(property "Tolerance" "1%"
			(at 309.88 158.75 0)
			(effects
				(font
					(size 1.27 1.27)
				)
				(justify left bottom)
				(hide yes)
			)
		)
		(pin "1"
		)
		(pin "2"
		)
		(instances
			(project "data-center-rdimm-ddr5-tester"
				(path ""
					(reference "R187")
					(unit 1)
				)
			)
		)
	)
	(symbol
		(lib_id "antmicroFuses:F_1.25A_0603")
		(at 351.79 78.74 0)
		(unit 1)
		(exclude_from_sim no)
		(in_bom yes)
		(on_board yes)
		(dnp no)
		(fields_autoplaced yes)
		(property "Reference" "F3"
			(at 354.33 73.66 0)
			(effects
				(font
					(size 1.27 1.27)
					(thickness 0.15)
				)
			)
		)
		(property "Value" "F_1.25A_0603"
			(at 375.92 83.82 0)
			(effects
				(font
					(size 1.27 1.27)
					(thickness 0.15)
				)
				(justify left bottom)
				(hide yes)
			)
		)
		(property "Footprint" "antmicro-footprints:F_0603_1608Metric"
			(at 375.92 86.36 0)
			(effects
				(font
					(size 1.27 1.27)
					(thickness 0.15)
				)
				(justify left bottom)
				(hide yes)
			)
		)
		(property "Datasheet" "https://www.littelfuse.com/~/media/electronics/datasheets/fuses/littelfuse_fuse_467_datasheet.pdf.pdf"
			(at 375.92 88.9 0)
			(effects
				(font
					(size 1.27 1.27)
					(thickness 0.15)
				)
				(justify left bottom)
				(hide yes)
			)
		)
		(property "Description" ""
			(at 351.79 78.74 0)
			(effects
				(font
					(size 1.27 1.27)
				)
				(hide yes)
			)
		)
		(property "MPN" "04671.25NR"
			(at 354.33 76.2 0)
			(effects
				(font
					(size 1.27 1.27)
					(thickness 0.15)
				)
			)
		)
		(property "Manufacturer" "Littelfuse"
			(at 375.92 93.98 0)
			(effects
				(font
					(size 1.27 1.27)
					(thickness 0.15)
				)
				(justify left bottom)
				(hide yes)
			)
		)
		(property "Author" "Antmicro"
			(at 375.92 96.52 0)
			(effects
				(font
					(size 1.27 1.27)
					(thickness 0.15)
				)
				(justify left bottom)
				(hide yes)
			)
		)
		(property "License" "Apache-2.0"
			(at 375.92 99.06 0)
			(effects
				(font
					(size 1.27 1.27)
					(thickness 0.15)
				)
				(justify left bottom)
				(hide yes)
			)
		)
		(pin "1"
		)
		(pin "2"
		)
		(instances
			(project "data-center-rdimm-ddr5-tester"
				(path ""
					(reference "F3")
					(unit 1)
				)
			)
		)
	)
	(symbol
		(lib_id "antmicroResistors0402:R_0R_0402")
		(at 176.53 266.7 0)
		(unit 1)
		(exclude_from_sim no)
		(in_bom yes)
		(on_board yes)
		(dnp no)
		(property "Reference" "R137"
			(at 184.15 265.43 0)
			(effects
				(font
					(size 1.27 1.27)
					(thickness 0.15)
				)
			)
		)
		(property "Value" "R_0R_0402"
			(at 196.85 279.4 0)
			(effects
				(font
					(size 1.27 1.27)
					(thickness 0.15)
				)
				(justify left bottom)
				(hide yes)
			)
		)
		(property "Footprint" "antmicro-footprints:R_0402_1005Metric"
			(at 196.85 281.94 0)
			(effects
				(font
					(size 1.27 1.27)
					(thickness 0.15)
				)
				(justify left bottom)
				(hide yes)
			)
		)
		(property "Datasheet" "https://industrial.panasonic.com/cdbs/www-data/pdf/RDA0000/AOA0000C301.pdf"
			(at 196.85 284.48 0)
			(effects
				(font
					(size 1.27 1.27)
					(thickness 0.15)
				)
				(justify left bottom)
				(hide yes)
			)
		)
		(property "Description" ""
			(at 176.53 266.7 0)
			(effects
				(font
					(size 1.27 1.27)
				)
				(hide yes)
			)
		)
		(property "MPN" "ERJ2GE0R00X"
			(at 196.85 287.02 0)
			(effects
				(font
					(size 1.27 1.27)
					(thickness 0.15)
				)
				(justify left bottom)
				(hide yes)
			)
		)
		(property "Manufacturer" "Panasonic"
			(at 196.85 289.56 0)
			(effects
				(font
					(size 1.27 1.27)
					(thickness 0.15)
				)
				(justify left bottom)
				(hide yes)
			)
		)
		(property "License" "Apache-2.0"
			(at 196.85 292.1 0)
			(effects
				(font
					(size 1.27 1.27)
					(thickness 0.15)
				)
				(justify left bottom)
				(hide yes)
			)
		)
		(property "Author" "Antmicro"
			(at 196.85 294.64 0)
			(effects
				(font
					(size 1.27 1.27)
					(thickness 0.15)
				)
				(justify left bottom)
				(hide yes)
			)
		)
		(property "Val" "0R"
			(at 175.26 265.43 0)
			(effects
				(font
					(size 1.27 1.27)
					(thickness 0.15)
				)
			)
		)
		(property "Tolerance" "~"
			(at 196.85 276.86 0)
			(effects
				(font
					(size 1.27 1.27)
				)
				(justify left bottom)
				(hide yes)
			)
		)
		(property "Current" "1A"
			(at 196.85 297.18 0)
			(effects
				(font
					(size 1.27 1.27)
					(thickness 0.15)
				)
				(justify left bottom)
				(hide yes)
			)
		)
		(pin "1"
		)
		(pin "2"
		)
		(instances
			(project "data-center-rdimm-ddr5-tester"
				(path ""
					(reference "R137")
					(unit 1)
				)
			)
		)
	)
	(symbol
		(lib_id "antmicropower:GND")
		(at 370.84 104.14 0)
		(unit 1)
		(exclude_from_sim no)
		(in_bom yes)
		(on_board yes)
		(dnp no)
		(fields_autoplaced yes)
		(property "Reference" "#PWR0544"
			(at 370.84 110.49 0)
			(effects
				(font
					(size 1.27 1.27)
				)
				(hide yes)
			)
		)
		(property "Value" "GND"
			(at 368.935 108.585 0)
			(effects
				(font
					(size 1.27 1.27)
					(thickness 0.15)
				)
				(justify left bottom)
			)
		)
		(property "Footprint" ""
			(at 379.73 111.76 0)
			(effects
				(font
					(size 1.27 1.27)
					(thickness 0.15)
				)
				(justify left bottom)
				(hide yes)
			)
		)
		(property "Datasheet" ""
			(at 379.73 116.84 0)
			(effects
				(font
					(size 1.27 1.27)
					(thickness 0.15)
				)
				(justify left bottom)
				(hide yes)
			)
		)
		(property "Description" ""
			(at 370.84 104.14 0)
			(effects
				(font
					(size 1.27 1.27)
				)
				(hide yes)
			)
		)
		(property "Author" "Antmicro"
			(at 379.73 109.22 0)
			(effects
				(font
					(size 1.27 1.27)
					(thickness 0.15)
				)
				(justify left bottom)
				(hide yes)
			)
		)
		(property "License" "Apache-2.0"
			(at 379.73 111.76 0)
			(effects
				(font
					(size 1.27 1.27)
					(thickness 0.15)
				)
				(justify left bottom)
				(hide yes)
			)
		)
		(pin "1"
		)
		(instances
			(project "data-center-rdimm-ddr5-tester"
				(path ""
					(reference "#PWR0544")
					(unit 1)
				)
			)
		)
	)
	(symbol
		(lib_id "antmicroResistors0402:R_10k_0402")
		(at 314.96 39.37 90)
		(unit 1)
		(exclude_from_sim no)
		(in_bom yes)
		(on_board yes)
		(dnp no)
		(fields_autoplaced yes)
		(property "Reference" "R170"
			(at 316.611 35.9994 90)
			(effects
				(font
					(size 1.27 1.27)
					(thickness 0.15)
				)
				(justify right)
			)
		)
		(property "Value" "R_10k_0402"
			(at 327.66 19.05 0)
			(effects
				(font
					(size 1.27 1.27)
					(thickness 0.15)
				)
				(justify left bottom)
				(hide yes)
			)
		)
		(property "Footprint" "antmicro-footprints:R_0402_1005Metric"
			(at 330.2 19.05 0)
			(effects
				(font
					(size 1.27 1.27)
					(thickness 0.15)
				)
				(justify left bottom)
				(hide yes)
			)
		)
		(property "Datasheet" "https://www.bourns.com/docs/product-datasheets/cr.pdf"
			(at 332.74 19.05 0)
			(effects
				(font
					(size 1.27 1.27)
					(thickness 0.15)
				)
				(justify left bottom)
				(hide yes)
			)
		)
		(property "Description" ""
			(at 314.96 39.37 0)
			(effects
				(font
					(size 1.27 1.27)
				)
				(hide yes)
			)
		)
		(property "MPN" "CR0402-FX-1002GLF"
			(at 335.28 19.05 0)
			(effects
				(font
					(size 1.27 1.27)
					(thickness 0.15)
				)
				(justify left bottom)
				(hide yes)
			)
		)
		(property "Manufacturer" "Bourns"
			(at 337.82 19.05 0)
			(effects
				(font
					(size 1.27 1.27)
					(thickness 0.15)
				)
				(justify left bottom)
				(hide yes)
			)
		)
		(property "License" "Apache-2.0"
			(at 340.36 19.05 0)
			(effects
				(font
					(size 1.27 1.27)
					(thickness 0.15)
				)
				(justify left bottom)
				(hide yes)
			)
		)
		(property "Author" "Antmicro"
			(at 342.9 19.05 0)
			(effects
				(font
					(size 1.27 1.27)
					(thickness 0.15)
				)
				(justify left bottom)
				(hide yes)
			)
		)
		(property "Val" "10k"
			(at 316.611 38.5231 90)
			(effects
				(font
					(size 1.27 1.27)
					(thickness 0.15)
				)
				(justify right)
			)
		)
		(property "Tolerance" "1%"
			(at 325.12 19.05 0)
			(effects
				(font
					(size 1.27 1.27)
				)
				(justify left bottom)
				(hide yes)
			)
		)
		(pin "1"
		)
		(pin "2"
		)
		(instances
			(project "data-center-rdimm-ddr5-tester"
				(path ""
					(reference "R170")
					(unit 1)
				)
			)
		)
	)
	(symbol
		(lib_id "antmicroResistors0402:R_47k_0402")
		(at 119.38 153.67 90)
		(unit 1)
		(exclude_from_sim no)
		(in_bom yes)
		(on_board yes)
		(dnp no)
		(property "Reference" "R160"
			(at 118.11 149.86 90)
			(effects
				(font
					(size 1.27 1.27)
				)
				(justify left)
			)
		)
		(property "Value" "R_47k_0402"
			(at 132.08 133.35 0)
			(effects
				(font
					(size 1.27 1.27)
					(thickness 0.15)
				)
				(justify left bottom)
				(hide yes)
			)
		)
		(property "Footprint" "antmicro-footprints:R_0402_1005Metric"
			(at 134.62 133.35 0)
			(effects
				(font
					(size 1.27 1.27)
					(thickness 0.15)
				)
				(justify left bottom)
				(hide yes)
			)
		)
		(property "Datasheet" "https://www.bourns.com/docs/product-datasheets/cr.pdf"
			(at 137.16 133.35 0)
			(effects
				(font
					(size 1.27 1.27)
					(thickness 0.15)
				)
				(justify left bottom)
				(hide yes)
			)
		)
		(property "Description" ""
			(at 119.38 153.67 0)
			(effects
				(font
					(size 1.27 1.27)
				)
				(hide yes)
			)
		)
		(property "Manufacturer" "Bourns"
			(at 142.24 133.35 0)
			(effects
				(font
					(size 1.27 1.27)
					(thickness 0.15)
				)
				(justify left bottom)
				(hide yes)
			)
		)
		(property "MPN" "CR0402-FX-4702GLF"
			(at 139.7 133.35 0)
			(effects
				(font
					(size 1.27 1.27)
					(thickness 0.15)
				)
				(justify left bottom)
				(hide yes)
			)
		)
		(property "Val" "47k"
			(at 118.11 152.4 90)
			(effects
				(font
					(size 1.27 1.27)
					(thickness 0.15)
				)
				(justify left)
			)
		)
		(property "License" "Apache-2.0"
			(at 144.78 133.35 0)
			(effects
				(font
					(size 1.27 1.27)
					(thickness 0.15)
				)
				(justify left bottom)
				(hide yes)
			)
		)
		(property "Author" "Antmicro"
			(at 147.32 133.35 0)
			(effects
				(font
					(size 1.27 1.27)
					(thickness 0.15)
				)
				(justify left bottom)
				(hide yes)
			)
		)
		(property "Tolerance" "1%"
			(at 129.54 133.35 0)
			(effects
				(font
					(size 1.27 1.27)
				)
				(justify left bottom)
				(hide yes)
			)
		)
		(pin "1"
		)
		(pin "2"
		)
		(instances
			(project "data-center-rdimm-ddr5-tester"
				(path ""
					(reference "R160")
					(unit 1)
				)
			)
		)
	)
	(symbol
		(lib_id "antmicropower:+3V3_AON")
		(at 88.9 133.35 0)
		(unit 1)
		(exclude_from_sim no)
		(in_bom yes)
		(on_board yes)
		(dnp no)
		(property "Reference" "#PWR0329"
			(at 88.9 137.16 0)
			(effects
				(font
					(size 1.27 1.27)
				)
				(hide yes)
			)
		)
		(property "Value" "+3V3_AON"
			(at 88.9 129.54 0)
			(effects
				(font
					(size 1.27 1.27)
				)
			)
		)
		(property "Footprint" ""
			(at 88.9 133.35 0)
			(effects
				(font
					(size 1.27 1.27)
				)
				(hide yes)
			)
		)
		(property "Datasheet" ""
			(at 88.9 133.35 0)
			(effects
				(font
					(size 1.27 1.27)
				)
				(hide yes)
			)
		)
		(property "Description" ""
			(at 88.9 133.35 0)
			(effects
				(font
					(size 1.27 1.27)
				)
				(hide yes)
			)
		)
		(pin "1"
		)
		(instances
			(project "data-center-rdimm-ddr5-tester"
				(path ""
					(reference "#PWR0329")
					(unit 1)
				)
			)
		)
	)
	(symbol
		(lib_id "antmicropower:+3V3_AON")
		(at 171.45 256.54 0)
		(unit 1)
		(exclude_from_sim no)
		(in_bom yes)
		(on_board yes)
		(dnp no)
		(property "Reference" "#PWR0285"
			(at 171.45 260.35 0)
			(effects
				(font
					(size 1.27 1.27)
				)
				(hide yes)
			)
		)
		(property "Value" "+3V3_AON"
			(at 171.45 252.73 0)
			(effects
				(font
					(size 1.27 1.27)
				)
			)
		)
		(property "Footprint" ""
			(at 171.45 256.54 0)
			(effects
				(font
					(size 1.27 1.27)
				)
				(hide yes)
			)
		)
		(property "Datasheet" ""
			(at 171.45 256.54 0)
			(effects
				(font
					(size 1.27 1.27)
				)
				(hide yes)
			)
		)
		(property "Description" ""
			(at 171.45 256.54 0)
			(effects
				(font
					(size 1.27 1.27)
				)
				(hide yes)
			)
		)
		(pin "1"
		)
		(instances
			(project "data-center-rdimm-ddr5-tester"
				(path ""
					(reference "#PWR0285")
					(unit 1)
				)
			)
		)
	)
	(symbol
		(lib_id "antmicropower:GND")
		(at 130.81 101.6 0)
		(unit 1)
		(exclude_from_sim no)
		(in_bom yes)
		(on_board yes)
		(dnp no)
		(fields_autoplaced yes)
		(property "Reference" "#PWR0299"
			(at 130.81 107.95 0)
			(effects
				(font
					(size 1.27 1.27)
				)
				(hide yes)
			)
		)
		(property "Value" "GND"
			(at 128.905 106.045 0)
			(effects
				(font
					(size 1.27 1.27)
					(thickness 0.15)
				)
				(justify left bottom)
			)
		)
		(property "Footprint" ""
			(at 139.7 109.22 0)
			(effects
				(font
					(size 1.27 1.27)
					(thickness 0.15)
				)
				(justify left bottom)
				(hide yes)
			)
		)
		(property "Datasheet" ""
			(at 139.7 114.3 0)
			(effects
				(font
					(size 1.27 1.27)
					(thickness 0.15)
				)
				(justify left bottom)
				(hide yes)
			)
		)
		(property "Description" ""
			(at 130.81 101.6 0)
			(effects
				(font
					(size 1.27 1.27)
				)
				(hide yes)
			)
		)
		(property "Author" "Antmicro"
			(at 139.7 106.68 0)
			(effects
				(font
					(size 1.27 1.27)
					(thickness 0.15)
				)
				(justify left bottom)
				(hide yes)
			)
		)
		(property "License" "Apache-2.0"
			(at 139.7 109.22 0)
			(effects
				(font
					(size 1.27 1.27)
					(thickness 0.15)
				)
				(justify left bottom)
				(hide yes)
			)
		)
		(pin "1"
		)
		(instances
			(project "data-center-rdimm-ddr5-tester"
				(path ""
					(reference "#PWR0299")
					(unit 1)
				)
			)
		)
	)
	(symbol
		(lib_id "antmicroCapacitors0402:C_100n_0402")
		(at 53.34 85.09 90)
		(unit 1)
		(exclude_from_sim no)
		(in_bom yes)
		(on_board yes)
		(dnp no)
		(fields_autoplaced yes)
		(property "Reference" "C170"
			(at 55.88 81.2735 90)
			(effects
				(font
					(size 1.27 1.27)
				)
				(justify right)
			)
		)
		(property "Value" "C_100n_0402"
			(at 63.5 64.77 0)
			(effects
				(font
					(size 1.27 1.27)
					(thickness 0.15)
				)
				(justify left bottom)
				(hide yes)
			)
		)
		(property "Footprint" "antmicro-footprints:C_0402_1005Metric"
			(at 66.04 64.77 0)
			(effects
				(font
					(size 1.27 1.27)
					(thickness 0.15)
				)
				(justify left bottom)
				(hide yes)
			)
		)
		(property "Datasheet" "https://www.murata.com/products/productdetail?partno=GRM155R61H104KE14%23"
			(at 68.58 64.77 0)
			(effects
				(font
					(size 1.27 1.27)
					(thickness 0.15)
				)
				(justify left bottom)
				(hide yes)
			)
		)
		(property "Description" ""
			(at 53.34 85.09 0)
			(effects
				(font
					(size 1.27 1.27)
				)
				(hide yes)
			)
		)
		(property "Manufacturer" "Murata"
			(at 73.66 64.77 0)
			(effects
				(font
					(size 1.27 1.27)
					(thickness 0.15)
				)
				(justify left bottom)
				(hide yes)
			)
		)
		(property "MPN" "GRM155R61H104KE14D"
			(at 71.12 64.77 0)
			(effects
				(font
					(size 1.27 1.27)
					(thickness 0.15)
				)
				(justify left bottom)
				(hide yes)
			)
		)
		(property "Val" "100n"
			(at 55.88 83.8135 90)
			(effects
				(font
					(size 1.27 1.27)
					(thickness 0.15)
				)
				(justify right)
			)
		)
		(property "License" "Apache-2.0"
			(at 76.2 64.77 0)
			(effects
				(font
					(size 1.27 1.27)
					(thickness 0.15)
				)
				(justify left bottom)
				(hide yes)
			)
		)
		(property "Author" "Antmicro"
			(at 78.74 64.77 0)
			(effects
				(font
					(size 1.27 1.27)
					(thickness 0.15)
				)
				(justify left bottom)
				(hide yes)
			)
		)
		(property "Voltage" "50V"
			(at 81.28 64.77 0)
			(effects
				(font
					(size 1.27 1.27)
				)
				(justify left bottom)
				(hide yes)
			)
		)
		(property "Dielectric" "X5R"
			(at 83.82 64.77 0)
			(effects
				(font
					(size 1.27 1.27)
				)
				(justify left bottom)
				(hide yes)
			)
		)
		(pin "1"
		)
		(pin "2"
		)
		(instances
			(project "data-center-rdimm-ddr5-tester"
				(path ""
					(reference "C170")
					(unit 1)
				)
			)
		)
	)
	(symbol
		(lib_id "antmicroCapacitors0603:C_1u_25V_0603")
		(at 124.46 62.23 90)
		(unit 1)
		(exclude_from_sim no)
		(in_bom yes)
		(on_board yes)
		(dnp no)
		(property "Reference" "C179"
			(at 116.205 62.2397 90)
			(effects
				(font
					(size 1.27 1.27)
				)
				(justify right)
			)
		)
		(property "Value" "C_1u_25V_0603"
			(at 134.62 41.91 0)
			(effects
				(font
					(size 1.27 1.27)
					(thickness 0.15)
				)
				(justify left bottom)
				(hide yes)
			)
		)
		(property "Footprint" "antmicro-footprints:C_0603_1608Metric"
			(at 137.16 41.91 0)
			(effects
				(font
					(size 1.27 1.27)
					(thickness 0.15)
				)
				(justify left bottom)
				(hide yes)
			)
		)
		(property "Datasheet" "https://product.samsungsem.com/mlcc/CL10A105KA8NNN.do"
			(at 139.7 41.91 0)
			(effects
				(font
					(size 1.27 1.27)
					(thickness 0.15)
				)
				(justify left bottom)
				(hide yes)
			)
		)
		(property "Description" ""
			(at 124.46 62.23 0)
			(effects
				(font
					(size 1.27 1.27)
				)
				(hide yes)
			)
		)
		(property "Manufacturer" "Samsung Electro-Mechanics"
			(at 144.78 41.91 0)
			(effects
				(font
					(size 1.27 1.27)
					(thickness 0.15)
				)
				(justify left bottom)
				(hide yes)
			)
		)
		(property "MPN" "CL10A105KA8NNNC"
			(at 142.24 41.91 0)
			(effects
				(font
					(size 1.27 1.27)
					(thickness 0.15)
				)
				(justify left bottom)
				(hide yes)
			)
		)
		(property "Val" "1u"
			(at 116.205 64.77 90)
			(effects
				(font
					(size 1.27 1.27)
					(thickness 0.15)
				)
				(justify right)
			)
		)
		(property "License" "Apache-2.0"
			(at 147.32 41.91 0)
			(effects
				(font
					(size 1.27 1.27)
					(thickness 0.15)
				)
				(justify left bottom)
				(hide yes)
			)
		)
		(property "Author" "Antmicro"
			(at 149.86 41.91 0)
			(effects
				(font
					(size 1.27 1.27)
					(thickness 0.15)
				)
				(justify left bottom)
				(hide yes)
			)
		)
		(property "Voltage" "25V"
			(at 152.4 41.91 0)
			(effects
				(font
					(size 1.27 1.27)
				)
				(justify left bottom)
				(hide yes)
			)
		)
		(property "Dielectric" ""
			(at 154.94 41.91 0)
			(effects
				(font
					(size 1.27 1.27)
				)
				(justify left bottom)
				(hide yes)
			)
		)
		(pin "1"
		)
		(pin "2"
		)
		(instances
			(project "data-center-rdimm-ddr5-tester"
				(path ""
					(reference "C179")
					(unit 1)
				)
			)
		)
	)
	(symbol
		(lib_id "antmicroCapacitors0402:C_100n_0402")
		(at 257.81 191.77 90)
		(unit 1)
		(exclude_from_sim no)
		(in_bom yes)
		(on_board yes)
		(dnp no)
		(property "Reference" "C209"
			(at 258.445 187.325 90)
			(effects
				(font
					(size 1.27 1.27)
				)
				(justify right)
			)
		)
		(property "Value" "C_100n_0402"
			(at 267.97 171.45 0)
			(effects
				(font
					(size 1.27 1.27)
					(thickness 0.15)
				)
				(justify left bottom)
				(hide yes)
			)
		)
		(property "Footprint" "antmicro-footprints:C_0402_1005Metric"
			(at 270.51 171.45 0)
			(effects
				(font
					(size 1.27 1.27)
					(thickness 0.15)
				)
				(justify left bottom)
				(hide yes)
			)
		)
		(property "Datasheet" "https://www.murata.com/products/productdetail?partno=GRM155R61H104KE14%23"
			(at 273.05 171.45 0)
			(effects
				(font
					(size 1.27 1.27)
					(thickness 0.15)
				)
				(justify left bottom)
				(hide yes)
			)
		)
		(property "Description" ""
			(at 257.81 191.77 0)
			(effects
				(font
					(size 1.27 1.27)
				)
				(hide yes)
			)
		)
		(property "Manufacturer" "Murata"
			(at 278.13 171.45 0)
			(effects
				(font
					(size 1.27 1.27)
					(thickness 0.15)
				)
				(justify left bottom)
				(hide yes)
			)
		)
		(property "MPN" "GRM155R61H104KE14D"
			(at 275.59 171.45 0)
			(effects
				(font
					(size 1.27 1.27)
					(thickness 0.15)
				)
				(justify left bottom)
				(hide yes)
			)
		)
		(property "Val" "100n"
			(at 258.445 191.135 90)
			(effects
				(font
					(size 1.27 1.27)
					(thickness 0.15)
				)
				(justify right)
			)
		)
		(property "License" "Apache-2.0"
			(at 280.67 171.45 0)
			(effects
				(font
					(size 1.27 1.27)
					(thickness 0.15)
				)
				(justify left bottom)
				(hide yes)
			)
		)
		(property "Author" "Antmicro"
			(at 283.21 171.45 0)
			(effects
				(font
					(size 1.27 1.27)
					(thickness 0.15)
				)
				(justify left bottom)
				(hide yes)
			)
		)
		(property "Voltage" "50V"
			(at 285.75 171.45 0)
			(effects
				(font
					(size 1.27 1.27)
				)
				(justify left bottom)
				(hide yes)
			)
		)
		(property "Dielectric" "X5R"
			(at 288.29 171.45 0)
			(effects
				(font
					(size 1.27 1.27)
				)
				(justify left bottom)
				(hide yes)
			)
		)
		(pin "1"
		)
		(pin "2"
		)
		(instances
			(project "data-center-rdimm-ddr5-tester"
				(path ""
					(reference "C209")
					(unit 1)
				)
			)
		)
	)
	(symbol
		(lib_id "antmicroResistors0402:R_47k_0402")
		(at 77.47 250.19 90)
		(unit 1)
		(exclude_from_sim no)
		(in_bom yes)
		(on_board yes)
		(dnp no)
		(fields_autoplaced yes)
		(property "Reference" "R235"
			(at 79.121 246.8194 90)
			(effects
				(font
					(size 1.27 1.27)
				)
				(justify right)
			)
		)
		(property "Value" "R_47k_0402"
			(at 90.17 229.87 0)
			(effects
				(font
					(size 1.27 1.27)
					(thickness 0.15)
				)
				(justify left bottom)
				(hide yes)
			)
		)
		(property "Footprint" "antmicro-footprints:R_0402_1005Metric"
			(at 92.71 229.87 0)
			(effects
				(font
					(size 1.27 1.27)
					(thickness 0.15)
				)
				(justify left bottom)
				(hide yes)
			)
		)
		(property "Datasheet" "https://www.bourns.com/docs/product-datasheets/cr.pdf"
			(at 95.25 229.87 0)
			(effects
				(font
					(size 1.27 1.27)
					(thickness 0.15)
				)
				(justify left bottom)
				(hide yes)
			)
		)
		(property "Description" ""
			(at 77.47 250.19 0)
			(effects
				(font
					(size 1.27 1.27)
				)
				(hide yes)
			)
		)
		(property "Manufacturer" "Bourns"
			(at 100.33 229.87 0)
			(effects
				(font
					(size 1.27 1.27)
					(thickness 0.15)
				)
				(justify left bottom)
				(hide yes)
			)
		)
		(property "MPN" "CR0402-FX-4702GLF"
			(at 97.79 229.87 0)
			(effects
				(font
					(size 1.27 1.27)
					(thickness 0.15)
				)
				(justify left bottom)
				(hide yes)
			)
		)
		(property "Val" "47k"
			(at 79.121 249.3497 90)
			(effects
				(font
					(size 1.27 1.27)
					(thickness 0.15)
				)
				(justify right)
			)
		)
		(property "License" "Apache-2.0"
			(at 102.87 229.87 0)
			(effects
				(font
					(size 1.27 1.27)
					(thickness 0.15)
				)
				(justify left bottom)
				(hide yes)
			)
		)
		(property "Author" "Antmicro"
			(at 105.41 229.87 0)
			(effects
				(font
					(size 1.27 1.27)
					(thickness 0.15)
				)
				(justify left bottom)
				(hide yes)
			)
		)
		(property "Tolerance" "1%"
			(at 87.63 229.87 0)
			(effects
				(font
					(size 1.27 1.27)
				)
				(justify left bottom)
				(hide yes)
			)
		)
		(pin "1"
		)
		(pin "2"
		)
		(instances
			(project "data-center-rdimm-ddr5-tester"
				(path ""
					(reference "R235")
					(unit 1)
				)
			)
		)
	)
	(symbol
		(lib_id "antmicropower:+5V")
		(at 314.96 33.02 0)
		(unit 1)
		(exclude_from_sim no)
		(in_bom yes)
		(on_board yes)
		(dnp no)
		(fields_autoplaced yes)
		(property "Reference" "#PWR0266"
			(at 314.96 36.83 0)
			(effects
				(font
					(size 1.27 1.27)
				)
				(hide yes)
			)
		)
		(property "Value" "+5V"
			(at 314.96 29.4456 0)
			(effects
				(font
					(size 1.27 1.27)
					(thickness 0.15)
				)
			)
		)
		(property "Footprint" ""
			(at 330.2 40.64 0)
			(effects
				(font
					(size 1.27 1.27)
					(thickness 0.15)
				)
				(justify left bottom)
				(hide yes)
			)
		)
		(property "Datasheet" ""
			(at 330.2 43.18 0)
			(effects
				(font
					(size 1.27 1.27)
					(thickness 0.15)
				)
				(justify left bottom)
				(hide yes)
			)
		)
		(property "Description" ""
			(at 314.96 33.02 0)
			(effects
				(font
					(size 1.27 1.27)
				)
				(hide yes)
			)
		)
		(property "Author" "Antmicro"
			(at 330.2 40.64 0)
			(effects
				(font
					(size 1.27 1.27)
					(thickness 0.15)
				)
				(justify left bottom)
				(hide yes)
			)
		)
		(property "License" "Apache-2.0"
			(at 330.2 43.18 0)
			(effects
				(font
					(size 1.27 1.27)
					(thickness 0.15)
				)
				(justify left bottom)
				(hide yes)
			)
		)
		(pin "1"
		)
		(instances
			(project "data-center-rdimm-ddr5-tester"
				(path ""
					(reference "#PWR0266")
					(unit 1)
				)
			)
		)
	)
	(symbol
		(lib_id "antmicropower:GND")
		(at 92.71 245.11 0)
		(unit 1)
		(exclude_from_sim no)
		(in_bom yes)
		(on_board yes)
		(dnp no)
		(property "Reference" "#PWR0303"
			(at 92.71 251.46 0)
			(effects
				(font
					(size 1.27 1.27)
				)
				(hide yes)
			)
		)
		(property "Value" "GND"
			(at 90.805 249.555 0)
			(effects
				(font
					(size 1.27 1.27)
					(thickness 0.15)
				)
				(justify left bottom)
			)
		)
		(property "Footprint" ""
			(at 101.6 252.73 0)
			(effects
				(font
					(size 1.27 1.27)
					(thickness 0.15)
				)
				(justify left bottom)
				(hide yes)
			)
		)
		(property "Datasheet" ""
			(at 101.6 257.81 0)
			(effects
				(font
					(size 1.27 1.27)
					(thickness 0.15)
				)
				(justify left bottom)
				(hide yes)
			)
		)
		(property "Description" ""
			(at 92.71 245.11 0)
			(effects
				(font
					(size 1.27 1.27)
				)
				(hide yes)
			)
		)
		(property "Author" "Antmicro"
			(at 101.6 250.19 0)
			(effects
				(font
					(size 1.27 1.27)
					(thickness 0.15)
				)
				(justify left bottom)
				(hide yes)
			)
		)
		(property "License" "Apache-2.0"
			(at 101.6 252.73 0)
			(effects
				(font
					(size 1.27 1.27)
					(thickness 0.15)
				)
				(justify left bottom)
				(hide yes)
			)
		)
		(pin "1"
		)
		(instances
			(project "data-center-rdimm-ddr5-tester"
				(path ""
					(reference "#PWR0303")
					(unit 1)
				)
			)
		)
	)
	(symbol
		(lib_id "antmicroTestPoints:TP_1206_SMD_RCW-0C")
		(at 367.03 243.84 0)
		(unit 1)
		(exclude_from_sim no)
		(in_bom yes)
		(on_board yes)
		(dnp no)
		(fields_autoplaced yes)
		(property "Reference" "TP20"
			(at 371.602 243.0094 0)
			(effects
				(font
					(size 1.27 1.27)
					(thickness 0.15)
				)
				(justify left)
			)
		)
		(property "Value" "TP_1206_SMD_RCW-0C"
			(at 371.602 245.5331 0)
			(effects
				(font
					(size 1.27 1.27)
					(thickness 0.15)
				)
				(justify left)
				(hide yes)
			)
		)
		(property "Footprint" "antmicro-footprints:TP_1206_SMD_RCW-0C"
			(at 384.81 254 0)
			(effects
				(font
					(size 1.27 1.27)
					(thickness 0.15)
				)
				(justify left bottom)
				(hide yes)
			)
		)
		(property "Datasheet" "https://www.te.com/commerce/DocumentDelivery/DDEController?Action=srchrtrv&DocNm=1773266&DocType=DS&DocLang=English"
			(at 384.81 256.54 0)
			(effects
				(font
					(size 1.27 1.27)
					(thickness 0.15)
				)
				(justify left bottom)
				(hide yes)
			)
		)
		(property "Description" ""
			(at 367.03 243.84 0)
			(effects
				(font
					(size 1.27 1.27)
				)
				(hide yes)
			)
		)
		(property "MPN" "RCW-0C"
			(at 384.81 259.08 0)
			(effects
				(font
					(size 1.27 1.27)
					(thickness 0.15)
				)
				(justify left bottom)
				(hide yes)
			)
		)
		(property "Manufacturer" "TE Connectivity"
			(at 384.81 261.62 0)
			(effects
				(font
					(size 1.27 1.27)
					(thickness 0.15)
				)
				(justify left bottom)
				(hide yes)
			)
		)
		(property "Author" "Antmicro"
			(at 384.81 264.16 0)
			(effects
				(font
					(size 1.27 1.27)
					(thickness 0.15)
				)
				(justify left bottom)
				(hide yes)
			)
		)
		(property "License" "Apache-2.0"
			(at 384.81 266.7 0)
			(effects
				(font
					(size 1.27 1.27)
					(thickness 0.15)
				)
				(justify left bottom)
				(hide yes)
			)
		)
		(pin "1"
		)
		(instances
			(project "data-center-rdimm-ddr5-tester"
				(path ""
					(reference "TP20")
					(unit 1)
				)
			)
		)
	)
	(symbol
		(lib_id "antmicroWire2BoardConnectors:JST_SH_1x4_BM04B-SRSS-TB-LF-SN")
		(at 341.63 33.02 0)
		(unit 1)
		(exclude_from_sim no)
		(in_bom yes)
		(on_board yes)
		(dnp no)
		(property "Reference" "J8"
			(at 347.472 37.2694 0)
			(effects
				(font
					(size 1.27 1.27)
					(thickness 0.15)
				)
				(justify left)
			)
		)
		(property "Value" "JST_SH_1x4_BM04B-SRSS-TB-LF-SN"
			(at 361.95 40.64 0)
			(effects
				(font
					(size 1.27 1.27)
					(thickness 0.15)
				)
				(justify left bottom)
				(hide yes)
			)
		)
		(property "Footprint" "antmicro-footprints:Conn_JST_SH_1x4_BM04B-SRSS-TB-LF-SN"
			(at 361.95 43.18 0)
			(effects
				(font
					(size 1.27 1.27)
					(thickness 0.15)
				)
				(justify left bottom)
				(hide yes)
			)
		)
		(property "Datasheet" "https://www.jst-mfg.com/product/pdf/eng/eSH.pdf"
			(at 361.95 45.72 0)
			(effects
				(font
					(size 1.27 1.27)
					(thickness 0.15)
				)
				(justify left bottom)
				(hide yes)
			)
		)
		(property "Description" ""
			(at 341.63 33.02 0)
			(effects
				(font
					(size 1.27 1.27)
				)
				(hide yes)
			)
		)
		(property "MPN" "BM04B-SRSS-TB(LF)(SN) "
			(at 324.612 52.07 0)
			(effects
				(font
					(size 1.27 1.27)
					(thickness 0.15)
				)
				(justify left)
			)
		)
		(property "Manufacturer" "JST Automotive Connectors"
			(at 361.95 50.8 0)
			(effects
				(font
					(size 1.27 1.27)
					(thickness 0.15)
				)
				(justify left bottom)
				(hide yes)
			)
		)
		(property "Author" "Antmicro"
			(at 361.95 53.34 0)
			(effects
				(font
					(size 1.27 1.27)
					(thickness 0.15)
				)
				(justify left bottom)
				(hide yes)
			)
		)
		(property "License" "Apache-2.0"
			(at 361.95 55.88 0)
			(effects
				(font
					(size 1.27 1.27)
					(thickness 0.15)
				)
				(justify left bottom)
				(hide yes)
			)
		)
		(pin "1"
		)
		(pin "2"
		)
		(pin "3"
		)
		(pin "4"
		)
		(pin "MP"
		)
		(instances
			(project "data-center-rdimm-ddr5-tester"
				(path ""
					(reference "J8")
					(unit 1)
				)
			)
		)
	)
	(symbol
		(lib_id "antmicroCapacitors0402:C_100n_0402")
		(at 198.12 168.91 90)
		(mirror x)
		(unit 1)
		(exclude_from_sim no)
		(in_bom yes)
		(on_board yes)
		(dnp no)
		(fields_autoplaced yes)
		(property "Reference" "C203"
			(at 195.7959 170.6257 90)
			(effects
				(font
					(size 1.27 1.27)
				)
				(justify left)
			)
		)
		(property "Value" "C_100n_0402"
			(at 208.28 189.23 0)
			(effects
				(font
					(size 1.27 1.27)
					(thickness 0.15)
				)
				(justify left bottom)
				(hide yes)
			)
		)
		(property "Footprint" "antmicro-footprints:C_0402_1005Metric"
			(at 210.82 189.23 0)
			(effects
				(font
					(size 1.27 1.27)
					(thickness 0.15)
				)
				(justify left bottom)
				(hide yes)
			)
		)
		(property "Datasheet" "https://www.murata.com/products/productdetail?partno=GRM155R61H104KE14%23"
			(at 213.36 189.23 0)
			(effects
				(font
					(size 1.27 1.27)
					(thickness 0.15)
				)
				(justify left bottom)
				(hide yes)
			)
		)
		(property "Description" ""
			(at 198.12 168.91 0)
			(effects
				(font
					(size 1.27 1.27)
				)
				(hide yes)
			)
		)
		(property "Manufacturer" "Murata"
			(at 218.44 189.23 0)
			(effects
				(font
					(size 1.27 1.27)
					(thickness 0.15)
				)
				(justify left bottom)
				(hide yes)
			)
		)
		(property "MPN" "GRM155R61H104KE14D"
			(at 215.9 189.23 0)
			(effects
				(font
					(size 1.27 1.27)
					(thickness 0.15)
				)
				(justify left bottom)
				(hide yes)
			)
		)
		(property "Val" "100n"
			(at 195.7959 173.3842 90)
			(effects
				(font
					(size 1.27 1.27)
					(thickness 0.15)
				)
				(justify left)
			)
		)
		(property "License" "Apache-2.0"
			(at 220.98 189.23 0)
			(effects
				(font
					(size 1.27 1.27)
					(thickness 0.15)
				)
				(justify left bottom)
				(hide yes)
			)
		)
		(property "Author" "Antmicro"
			(at 223.52 189.23 0)
			(effects
				(font
					(size 1.27 1.27)
					(thickness 0.15)
				)
				(justify left bottom)
				(hide yes)
			)
		)
		(property "Voltage" "50V"
			(at 226.06 189.23 0)
			(effects
				(font
					(size 1.27 1.27)
				)
				(justify left bottom)
				(hide yes)
			)
		)
		(property "Dielectric" "X5R"
			(at 228.6 189.23 0)
			(effects
				(font
					(size 1.27 1.27)
				)
				(justify left bottom)
				(hide yes)
			)
		)
		(pin "1"
		)
		(pin "2"
		)
		(instances
			(project "data-center-rdimm-ddr5-tester"
				(path ""
					(reference "C203")
					(unit 1)
				)
			)
		)
	)
	(symbol
		(lib_id "antmicropower:GND")
		(at 204.47 195.58 0)
		(unit 1)
		(exclude_from_sim no)
		(in_bom yes)
		(on_board yes)
		(dnp no)
		(fields_autoplaced yes)
		(property "Reference" "#PWR0371"
			(at 204.47 201.93 0)
			(effects
				(font
					(size 1.27 1.27)
				)
				(hide yes)
			)
		)
		(property "Value" "GND"
			(at 202.565 200.025 0)
			(effects
				(font
					(size 1.27 1.27)
					(thickness 0.15)
				)
				(justify left bottom)
			)
		)
		(property "Footprint" ""
			(at 213.36 203.2 0)
			(effects
				(font
					(size 1.27 1.27)
					(thickness 0.15)
				)
				(justify left bottom)
				(hide yes)
			)
		)
		(property "Datasheet" ""
			(at 213.36 208.28 0)
			(effects
				(font
					(size 1.27 1.27)
					(thickness 0.15)
				)
				(justify left bottom)
				(hide yes)
			)
		)
		(property "Description" ""
			(at 204.47 195.58 0)
			(effects
				(font
					(size 1.27 1.27)
				)
				(hide yes)
			)
		)
		(property "Author" "Antmicro"
			(at 213.36 200.66 0)
			(effects
				(font
					(size 1.27 1.27)
					(thickness 0.15)
				)
				(justify left bottom)
				(hide yes)
			)
		)
		(property "License" "Apache-2.0"
			(at 213.36 203.2 0)
			(effects
				(font
					(size 1.27 1.27)
					(thickness 0.15)
				)
				(justify left bottom)
				(hide yes)
			)
		)
		(pin "1"
		)
		(instances
			(project "data-center-rdimm-ddr5-tester"
				(path ""
					(reference "#PWR0371")
					(unit 1)
				)
			)
		)
	)
	(symbol
		(lib_id "antmicropower:GND")
		(at 350.52 245.11 0)
		(mirror y)
		(unit 1)
		(exclude_from_sim no)
		(in_bom yes)
		(on_board yes)
		(dnp no)
		(fields_autoplaced yes)
		(property "Reference" "#PWR0340"
			(at 350.52 251.46 0)
			(effects
				(font
					(size 1.27 1.27)
				)
				(hide yes)
			)
		)
		(property "Value" "GND"
			(at 352.425 249.555 0)
			(effects
				(font
					(size 1.27 1.27)
					(thickness 0.15)
				)
				(justify left bottom)
			)
		)
		(property "Footprint" ""
			(at 341.63 252.73 0)
			(effects
				(font
					(size 1.27 1.27)
					(thickness 0.15)
				)
				(justify left bottom)
				(hide yes)
			)
		)
		(property "Datasheet" ""
			(at 341.63 257.81 0)
			(effects
				(font
					(size 1.27 1.27)
					(thickness 0.15)
				)
				(justify left bottom)
				(hide yes)
			)
		)
		(property "Description" ""
			(at 350.52 245.11 0)
			(effects
				(font
					(size 1.27 1.27)
				)
				(hide yes)
			)
		)
		(property "Author" "Antmicro"
			(at 341.63 250.19 0)
			(effects
				(font
					(size 1.27 1.27)
					(thickness 0.15)
				)
				(justify left bottom)
				(hide yes)
			)
		)
		(property "License" "Apache-2.0"
			(at 341.63 252.73 0)
			(effects
				(font
					(size 1.27 1.27)
					(thickness 0.15)
				)
				(justify left bottom)
				(hide yes)
			)
		)
		(pin "1"
		)
		(instances
			(project "data-center-rdimm-ddr5-tester"
				(path ""
					(reference "#PWR0340")
					(unit 1)
				)
			)
		)
	)
	(symbol
		(lib_id "antmicropower:GND")
		(at 250.19 95.25 0)
		(mirror y)
		(unit 1)
		(exclude_from_sim no)
		(in_bom yes)
		(on_board yes)
		(dnp no)
		(fields_autoplaced yes)
		(property "Reference" "#PWR0555"
			(at 250.19 101.6 0)
			(effects
				(font
					(size 1.27 1.27)
				)
				(hide yes)
			)
		)
		(property "Value" "GND"
			(at 252.095 96.52 0)
			(effects
				(font
					(size 1.27 1.27)
					(thickness 0.15)
				)
				(justify right)
			)
		)
		(property "Footprint" ""
			(at 241.3 102.87 0)
			(effects
				(font
					(size 1.27 1.27)
					(thickness 0.15)
				)
				(justify left bottom)
				(hide yes)
			)
		)
		(property "Datasheet" ""
			(at 241.3 107.95 0)
			(effects
				(font
					(size 1.27 1.27)
					(thickness 0.15)
				)
				(justify left bottom)
				(hide yes)
			)
		)
		(property "Description" ""
			(at 241.3 110.49 0)
			(effects
				(font
					(size 1.27 1.27)
				)
				(justify left bottom)
				(hide yes)
			)
		)
		(property "Author" "Antmicro"
			(at 241.3 102.87 0)
			(effects
				(font
					(size 1.27 1.27)
					(thickness 0.15)
				)
				(justify left bottom)
				(hide yes)
			)
		)
		(property "License" "Apache-2.0"
			(at 241.3 105.41 0)
			(effects
				(font
					(size 1.27 1.27)
					(thickness 0.15)
				)
				(justify left bottom)
				(hide yes)
			)
		)
		(pin "1"
		)
		(instances
			(project "data-center-rdimm-ddr5-tester"
				(path ""
					(reference "#PWR0555")
					(unit 1)
				)
			)
		)
	)
	(symbol
		(lib_id "antmicroCapacitors0603:C_1u_25V_0603")
		(at 189.23 41.91 90)
		(mirror x)
		(unit 1)
		(exclude_from_sim no)
		(in_bom yes)
		(on_board yes)
		(dnp no)
		(property "Reference" "C181"
			(at 189.865 42.545 90)
			(effects
				(font
					(size 1.27 1.27)
				)
				(justify right)
			)
		)
		(property "Value" "C_1u_25V_0603"
			(at 199.39 62.23 0)
			(effects
				(font
					(size 1.27 1.27)
					(thickness 0.15)
				)
				(justify left bottom)
				(hide yes)
			)
		)
		(property "Footprint" "antmicro-footprints:C_0603_1608Metric"
			(at 201.93 62.23 0)
			(effects
				(font
					(size 1.27 1.27)
					(thickness 0.15)
				)
				(justify left bottom)
				(hide yes)
			)
		)
		(property "Datasheet" "https://product.samsungsem.com/mlcc/CL10A105KA8NNN.do"
			(at 204.47 62.23 0)
			(effects
				(font
					(size 1.27 1.27)
					(thickness 0.15)
				)
				(justify left bottom)
				(hide yes)
			)
		)
		(property "Description" ""
			(at 189.23 41.91 0)
			(effects
				(font
					(size 1.27 1.27)
				)
				(hide yes)
			)
		)
		(property "Manufacturer" "Samsung Electro-Mechanics"
			(at 209.55 62.23 0)
			(effects
				(font
					(size 1.27 1.27)
					(thickness 0.15)
				)
				(justify left bottom)
				(hide yes)
			)
		)
		(property "MPN" "CL10A105KA8NNNC"
			(at 207.01 62.23 0)
			(effects
				(font
					(size 1.27 1.27)
					(thickness 0.15)
				)
				(justify left bottom)
				(hide yes)
			)
		)
		(property "Val" "1u"
			(at 189.865 46.355 90)
			(effects
				(font
					(size 1.27 1.27)
					(thickness 0.15)
				)
				(justify right)
			)
		)
		(property "License" "Apache-2.0"
			(at 212.09 62.23 0)
			(effects
				(font
					(size 1.27 1.27)
					(thickness 0.15)
				)
				(justify left bottom)
				(hide yes)
			)
		)
		(property "Author" "Antmicro"
			(at 214.63 62.23 0)
			(effects
				(font
					(size 1.27 1.27)
					(thickness 0.15)
				)
				(justify left bottom)
				(hide yes)
			)
		)
		(property "Voltage" "25V"
			(at 217.17 62.23 0)
			(effects
				(font
					(size 1.27 1.27)
				)
				(justify left bottom)
				(hide yes)
			)
		)
		(property "Dielectric" ""
			(at 219.71 62.23 0)
			(effects
				(font
					(size 1.27 1.27)
				)
				(justify left bottom)
				(hide yes)
			)
		)
		(pin "1"
		)
		(pin "2"
		)
		(instances
			(project "data-center-rdimm-ddr5-tester"
				(path ""
					(reference "C181")
					(unit 1)
				)
			)
		)
	)
	(symbol
		(lib_id "antmicroCapacitors0402:C_100n_0402")
		(at 93.98 140.97 90)
		(unit 1)
		(exclude_from_sim no)
		(in_bom yes)
		(on_board yes)
		(dnp no)
		(property "Reference" "C195"
			(at 95.25 136.525 90)
			(effects
				(font
					(size 1.27 1.27)
				)
				(justify right)
			)
		)
		(property "Value" "C_100n_0402"
			(at 104.14 120.65 0)
			(effects
				(font
					(size 1.27 1.27)
					(thickness 0.15)
				)
				(justify left bottom)
				(hide yes)
			)
		)
		(property "Footprint" "antmicro-footprints:C_0402_1005Metric"
			(at 106.68 120.65 0)
			(effects
				(font
					(size 1.27 1.27)
					(thickness 0.15)
				)
				(justify left bottom)
				(hide yes)
			)
		)
		(property "Datasheet" "https://www.murata.com/products/productdetail?partno=GRM155R61H104KE14%23"
			(at 109.22 120.65 0)
			(effects
				(font
					(size 1.27 1.27)
					(thickness 0.15)
				)
				(justify left bottom)
				(hide yes)
			)
		)
		(property "Description" ""
			(at 93.98 140.97 0)
			(effects
				(font
					(size 1.27 1.27)
				)
				(hide yes)
			)
		)
		(property "Manufacturer" "Murata"
			(at 114.3 120.65 0)
			(effects
				(font
					(size 1.27 1.27)
					(thickness 0.15)
				)
				(justify left bottom)
				(hide yes)
			)
		)
		(property "MPN" "GRM155R61H104KE14D"
			(at 111.76 120.65 0)
			(effects
				(font
					(size 1.27 1.27)
					(thickness 0.15)
				)
				(justify left bottom)
				(hide yes)
			)
		)
		(property "Val" "100n"
			(at 95.25 140.335 90)
			(effects
				(font
					(size 1.27 1.27)
					(thickness 0.15)
				)
				(justify right)
			)
		)
		(property "License" "Apache-2.0"
			(at 116.84 120.65 0)
			(effects
				(font
					(size 1.27 1.27)
					(thickness 0.15)
				)
				(justify left bottom)
				(hide yes)
			)
		)
		(property "Author" "Antmicro"
			(at 119.38 120.65 0)
			(effects
				(font
					(size 1.27 1.27)
					(thickness 0.15)
				)
				(justify left bottom)
				(hide yes)
			)
		)
		(property "Voltage" "50V"
			(at 121.92 120.65 0)
			(effects
				(font
					(size 1.27 1.27)
				)
				(justify left bottom)
				(hide yes)
			)
		)
		(property "Dielectric" "X5R"
			(at 124.46 120.65 0)
			(effects
				(font
					(size 1.27 1.27)
				)
				(justify left bottom)
				(hide yes)
			)
		)
		(pin "1"
		)
		(pin "2"
		)
		(instances
			(project "data-center-rdimm-ddr5-tester"
				(path ""
					(reference "C195")
					(unit 1)
				)
			)
		)
	)
	(symbol
		(lib_id "antmicroResistors0402:R_47k_0402")
		(at 309.88 179.07 90)
		(unit 1)
		(exclude_from_sim no)
		(in_bom yes)
		(on_board yes)
		(dnp no)
		(property "Reference" "R190"
			(at 311.15 175.26 90)
			(effects
				(font
					(size 1.27 1.27)
				)
				(justify right)
			)
		)
		(property "Value" "R_47k_0402"
			(at 322.58 158.75 0)
			(effects
				(font
					(size 1.27 1.27)
					(thickness 0.15)
				)
				(justify left bottom)
				(hide yes)
			)
		)
		(property "Footprint" "antmicro-footprints:R_0402_1005Metric"
			(at 325.12 158.75 0)
			(effects
				(font
					(size 1.27 1.27)
					(thickness 0.15)
				)
				(justify left bottom)
				(hide yes)
			)
		)
		(property "Datasheet" "https://www.bourns.com/docs/product-datasheets/cr.pdf"
			(at 327.66 158.75 0)
			(effects
				(font
					(size 1.27 1.27)
					(thickness 0.15)
				)
				(justify left bottom)
				(hide yes)
			)
		)
		(property "Description" ""
			(at 309.88 179.07 0)
			(effects
				(font
					(size 1.27 1.27)
				)
				(hide yes)
			)
		)
		(property "Manufacturer" "Bourns"
			(at 332.74 158.75 0)
			(effects
				(font
					(size 1.27 1.27)
					(thickness 0.15)
				)
				(justify left bottom)
				(hide yes)
			)
		)
		(property "MPN" "CR0402-FX-4702GLF"
			(at 330.2 158.75 0)
			(effects
				(font
					(size 1.27 1.27)
					(thickness 0.15)
				)
				(justify left bottom)
				(hide yes)
			)
		)
		(property "Val" "47k"
			(at 311.15 177.8 90)
			(effects
				(font
					(size 1.27 1.27)
					(thickness 0.15)
				)
				(justify right)
			)
		)
		(property "License" "Apache-2.0"
			(at 335.28 158.75 0)
			(effects
				(font
					(size 1.27 1.27)
					(thickness 0.15)
				)
				(justify left bottom)
				(hide yes)
			)
		)
		(property "Author" "Antmicro"
			(at 337.82 158.75 0)
			(effects
				(font
					(size 1.27 1.27)
					(thickness 0.15)
				)
				(justify left bottom)
				(hide yes)
			)
		)
		(property "Tolerance" "1%"
			(at 320.04 158.75 0)
			(effects
				(font
					(size 1.27 1.27)
				)
				(justify left bottom)
				(hide yes)
			)
		)
		(pin "1"
		)
		(pin "2"
		)
		(instances
			(project "data-center-rdimm-ddr5-tester"
				(path ""
					(reference "R190")
					(unit 1)
				)
			)
		)
	)
	(symbol
		(lib_id "antmicropower:GND")
		(at 262.89 176.53 0)
		(unit 1)
		(exclude_from_sim no)
		(in_bom yes)
		(on_board yes)
		(dnp no)
		(fields_autoplaced yes)
		(property "Reference" "#PWR0383"
			(at 262.89 182.88 0)
			(effects
				(font
					(size 1.27 1.27)
				)
				(hide yes)
			)
		)
		(property "Value" "GND"
			(at 260.985 180.975 0)
			(effects
				(font
					(size 1.27 1.27)
					(thickness 0.15)
				)
				(justify left bottom)
			)
		)
		(property "Footprint" ""
			(at 271.78 184.15 0)
			(effects
				(font
					(size 1.27 1.27)
					(thickness 0.15)
				)
				(justify left bottom)
				(hide yes)
			)
		)
		(property "Datasheet" ""
			(at 271.78 189.23 0)
			(effects
				(font
					(size 1.27 1.27)
					(thickness 0.15)
				)
				(justify left bottom)
				(hide yes)
			)
		)
		(property "Description" ""
			(at 262.89 176.53 0)
			(effects
				(font
					(size 1.27 1.27)
				)
				(hide yes)
			)
		)
		(property "Author" "Antmicro"
			(at 271.78 181.61 0)
			(effects
				(font
					(size 1.27 1.27)
					(thickness 0.15)
				)
				(justify left bottom)
				(hide yes)
			)
		)
		(property "License" "Apache-2.0"
			(at 271.78 184.15 0)
			(effects
				(font
					(size 1.27 1.27)
					(thickness 0.15)
				)
				(justify left bottom)
				(hide yes)
			)
		)
		(pin "1"
		)
		(instances
			(project "data-center-rdimm-ddr5-tester"
				(path ""
					(reference "#PWR0383")
					(unit 1)
				)
			)
		)
	)
	(symbol
		(lib_id "antmicropower:GND")
		(at 365.76 245.11 0)
		(mirror y)
		(unit 1)
		(exclude_from_sim no)
		(in_bom yes)
		(on_board yes)
		(dnp no)
		(fields_autoplaced yes)
		(property "Reference" "#PWR0339"
			(at 365.76 251.46 0)
			(effects
				(font
					(size 1.27 1.27)
				)
				(hide yes)
			)
		)
		(property "Value" "GND"
			(at 367.665 249.555 0)
			(effects
				(font
					(size 1.27 1.27)
					(thickness 0.15)
				)
				(justify left bottom)
			)
		)
		(property "Footprint" ""
			(at 356.87 252.73 0)
			(effects
				(font
					(size 1.27 1.27)
					(thickness 0.15)
				)
				(justify left bottom)
				(hide yes)
			)
		)
		(property "Datasheet" ""
			(at 356.87 257.81 0)
			(effects
				(font
					(size 1.27 1.27)
					(thickness 0.15)
				)
				(justify left bottom)
				(hide yes)
			)
		)
		(property "Description" ""
			(at 365.76 245.11 0)
			(effects
				(font
					(size 1.27 1.27)
				)
				(hide yes)
			)
		)
		(property "Author" "Antmicro"
			(at 356.87 250.19 0)
			(effects
				(font
					(size 1.27 1.27)
					(thickness 0.15)
				)
				(justify left bottom)
				(hide yes)
			)
		)
		(property "License" "Apache-2.0"
			(at 356.87 252.73 0)
			(effects
				(font
					(size 1.27 1.27)
					(thickness 0.15)
				)
				(justify left bottom)
				(hide yes)
			)
		)
		(pin "1"
		)
		(instances
			(project "data-center-rdimm-ddr5-tester"
				(path ""
					(reference "#PWR0339")
					(unit 1)
				)
			)
		)
	)
	(symbol
		(lib_id "antmicroResistors0402:R_47k_0402")
		(at 290.83 179.07 90)
		(unit 1)
		(exclude_from_sim no)
		(in_bom yes)
		(on_board yes)
		(dnp no)
		(property "Reference" "R184"
			(at 292.1 175.26 90)
			(effects
				(font
					(size 1.27 1.27)
				)
				(justify right)
			)
		)
		(property "Value" "R_47k_0402"
			(at 303.53 158.75 0)
			(effects
				(font
					(size 1.27 1.27)
					(thickness 0.15)
				)
				(justify left bottom)
				(hide yes)
			)
		)
		(property "Footprint" "antmicro-footprints:R_0402_1005Metric"
			(at 306.07 158.75 0)
			(effects
				(font
					(size 1.27 1.27)
					(thickness 0.15)
				)
				(justify left bottom)
				(hide yes)
			)
		)
		(property "Datasheet" "https://www.bourns.com/docs/product-datasheets/cr.pdf"
			(at 308.61 158.75 0)
			(effects
				(font
					(size 1.27 1.27)
					(thickness 0.15)
				)
				(justify left bottom)
				(hide yes)
			)
		)
		(property "Description" ""
			(at 290.83 179.07 0)
			(effects
				(font
					(size 1.27 1.27)
				)
				(hide yes)
			)
		)
		(property "Manufacturer" "Bourns"
			(at 313.69 158.75 0)
			(effects
				(font
					(size 1.27 1.27)
					(thickness 0.15)
				)
				(justify left bottom)
				(hide yes)
			)
		)
		(property "MPN" "CR0402-FX-4702GLF"
			(at 311.15 158.75 0)
			(effects
				(font
					(size 1.27 1.27)
					(thickness 0.15)
				)
				(justify left bottom)
				(hide yes)
			)
		)
		(property "Val" "47k"
			(at 292.1 177.8 90)
			(effects
				(font
					(size 1.27 1.27)
					(thickness 0.15)
				)
				(justify right)
			)
		)
		(property "License" "Apache-2.0"
			(at 316.23 158.75 0)
			(effects
				(font
					(size 1.27 1.27)
					(thickness 0.15)
				)
				(justify left bottom)
				(hide yes)
			)
		)
		(property "Author" "Antmicro"
			(at 318.77 158.75 0)
			(effects
				(font
					(size 1.27 1.27)
					(thickness 0.15)
				)
				(justify left bottom)
				(hide yes)
			)
		)
		(property "Tolerance" "1%"
			(at 300.99 158.75 0)
			(effects
				(font
					(size 1.27 1.27)
				)
				(justify left bottom)
				(hide yes)
			)
		)
		(pin "1"
		)
		(pin "2"
		)
		(instances
			(project "data-center-rdimm-ddr5-tester"
				(path ""
					(reference "R184")
					(unit 1)
				)
			)
		)
	)
	(symbol
		(lib_id "antmicropower:GND")
		(at 124.46 66.04 0)
		(unit 1)
		(exclude_from_sim no)
		(in_bom yes)
		(on_board yes)
		(dnp no)
		(fields_autoplaced yes)
		(property "Reference" "#PWR0298"
			(at 124.46 72.39 0)
			(effects
				(font
					(size 1.27 1.27)
				)
				(hide yes)
			)
		)
		(property "Value" "GND"
			(at 122.555 70.485 0)
			(effects
				(font
					(size 1.27 1.27)
					(thickness 0.15)
				)
				(justify left bottom)
			)
		)
		(property "Footprint" ""
			(at 133.35 73.66 0)
			(effects
				(font
					(size 1.27 1.27)
					(thickness 0.15)
				)
				(justify left bottom)
				(hide yes)
			)
		)
		(property "Datasheet" ""
			(at 133.35 78.74 0)
			(effects
				(font
					(size 1.27 1.27)
					(thickness 0.15)
				)
				(justify left bottom)
				(hide yes)
			)
		)
		(property "Description" ""
			(at 124.46 66.04 0)
			(effects
				(font
					(size 1.27 1.27)
				)
				(hide yes)
			)
		)
		(property "Author" "Antmicro"
			(at 133.35 71.12 0)
			(effects
				(font
					(size 1.27 1.27)
					(thickness 0.15)
				)
				(justify left bottom)
				(hide yes)
			)
		)
		(property "License" "Apache-2.0"
			(at 133.35 73.66 0)
			(effects
				(font
					(size 1.27 1.27)
					(thickness 0.15)
				)
				(justify left bottom)
				(hide yes)
			)
		)
		(pin "1"
		)
		(instances
			(project "data-center-rdimm-ddr5-tester"
				(path ""
					(reference "#PWR0298")
					(unit 1)
				)
			)
		)
	)
	(symbol
		(lib_id "antmicropower:GND")
		(at 238.76 53.34 0)
		(unit 1)
		(exclude_from_sim no)
		(in_bom yes)
		(on_board yes)
		(dnp no)
		(fields_autoplaced yes)
		(property "Reference" "#PWR0315"
			(at 238.76 59.69 0)
			(effects
				(font
					(size 1.27 1.27)
				)
				(hide yes)
			)
		)
		(property "Value" "GND"
			(at 236.855 57.785 0)
			(effects
				(font
					(size 1.27 1.27)
					(thickness 0.15)
				)
				(justify left bottom)
			)
		)
		(property "Footprint" ""
			(at 247.65 60.96 0)
			(effects
				(font
					(size 1.27 1.27)
					(thickness 0.15)
				)
				(justify left bottom)
				(hide yes)
			)
		)
		(property "Datasheet" ""
			(at 247.65 66.04 0)
			(effects
				(font
					(size 1.27 1.27)
					(thickness 0.15)
				)
				(justify left bottom)
				(hide yes)
			)
		)
		(property "Description" ""
			(at 238.76 53.34 0)
			(effects
				(font
					(size 1.27 1.27)
				)
				(hide yes)
			)
		)
		(property "Author" "Antmicro"
			(at 247.65 58.42 0)
			(effects
				(font
					(size 1.27 1.27)
					(thickness 0.15)
				)
				(justify left bottom)
				(hide yes)
			)
		)
		(property "License" "Apache-2.0"
			(at 247.65 60.96 0)
			(effects
				(font
					(size 1.27 1.27)
					(thickness 0.15)
				)
				(justify left bottom)
				(hide yes)
			)
		)
		(pin "1"
		)
		(instances
			(project "data-center-rdimm-ddr5-tester"
				(path ""
					(reference "#PWR0315")
					(unit 1)
				)
			)
		)
	)
	(symbol
		(lib_id "antmicroCapacitors0402:C_10u_6.3V_0402")
		(at 185.42 95.25 90)
		(unit 1)
		(exclude_from_sim no)
		(in_bom yes)
		(on_board yes)
		(dnp no)
		(property "Reference" "C329"
			(at 186.182 90.932 90)
			(effects
				(font
					(size 1.27 1.27)
					(thickness 0.15)
				)
				(justify right)
			)
		)
		(property "Value" "C_10u_6.3V_0402"
			(at 195.58 74.93 0)
			(effects
				(font
					(size 1.27 1.27)
					(thickness 0.15)
				)
				(justify left bottom)
				(hide yes)
			)
		)
		(property "Footprint" "antmicro-footprints:C_0402_1005Metric"
			(at 198.12 74.93 0)
			(effects
				(font
					(size 1.27 1.27)
					(thickness 0.15)
				)
				(justify left bottom)
				(hide yes)
			)
		)
		(property "Datasheet" "https://www.murata.com/products/productdetail?partno=GRM155R60J106ME15%23"
			(at 200.66 74.93 0)
			(effects
				(font
					(size 1.27 1.27)
					(thickness 0.15)
				)
				(justify left bottom)
				(hide yes)
			)
		)
		(property "Description" ""
			(at 185.42 95.25 0)
			(effects
				(font
					(size 1.27 1.27)
				)
			)
		)
		(property "MPN" "GRM155R60J106ME15D"
			(at 203.2 74.93 0)
			(effects
				(font
					(size 1.27 1.27)
					(thickness 0.15)
				)
				(justify left bottom)
				(hide yes)
			)
		)
		(property "Manufacturer" "Murata"
			(at 205.74 74.93 0)
			(effects
				(font
					(size 1.27 1.27)
					(thickness 0.15)
				)
				(justify left bottom)
				(hide yes)
			)
		)
		(property "License" "Apache-2.0"
			(at 208.28 74.93 0)
			(effects
				(font
					(size 1.27 1.27)
					(thickness 0.15)
				)
				(justify left bottom)
				(hide yes)
			)
		)
		(property "Author" "Antmicro"
			(at 210.82 74.93 0)
			(effects
				(font
					(size 1.27 1.27)
					(thickness 0.15)
				)
				(justify left bottom)
				(hide yes)
			)
		)
		(property "Val" "10u"
			(at 186.436 94.742 90)
			(effects
				(font
					(size 1.27 1.27)
					(thickness 0.15)
				)
				(justify right)
			)
		)
		(property "Voltage" "6.3V"
			(at 213.36 74.93 0)
			(effects
				(font
					(size 1.27 1.27)
				)
				(justify left bottom)
				(hide yes)
			)
		)
		(property "Dielectric" "X5R"
			(at 215.9 74.93 0)
			(effects
				(font
					(size 1.27 1.27)
				)
				(justify left bottom)
				(hide yes)
			)
		)
		(pin "1"
		)
		(pin "2"
		)
		(instances
			(project "data-center-rdimm-ddr5-tester"
				(path ""
					(reference "C329")
					(unit 1)
				)
			)
		)
	)
	(symbol
		(lib_id "antmicroTransistorsFETsMOSFETsSingle:SI7613DN-T1-GE3")
		(at 115.57 52.07 90)
		(unit 1)
		(exclude_from_sim no)
		(in_bom yes)
		(on_board yes)
		(dnp no)
		(fields_autoplaced yes)
		(property "Reference" "Q12"
			(at 113.03 38.1 90)
			(effects
				(font
					(size 1.27 1.27)
					(thickness 0.15)
				)
			)
		)
		(property "Value" "SI7613DN-T1-GE3"
			(at 113.03 36.83 0)
			(effects
				(font
					(size 1.27 1.27)
					(thickness 0.15)
				)
				(justify left bottom)
				(hide yes)
			)
		)
		(property "Footprint" "antmicro-footprints:Vishay_PowerPAK_1212-8_Single"
			(at 114.3 36.83 0)
			(effects
				(font
					(size 1.27 1.27)
					(thickness 0.15)
				)
				(justify left bottom)
				(hide yes)
			)
		)
		(property "Datasheet" "https://www.vishay.com/docs/64809/si7613dn.pdf"
			(at 116.84 36.83 0)
			(effects
				(font
					(size 1.27 1.27)
					(thickness 0.15)
				)
				(justify left bottom)
				(hide yes)
			)
		)
		(property "Description" ""
			(at 115.57 52.07 0)
			(effects
				(font
					(size 1.27 1.27)
				)
				(hide yes)
			)
		)
		(property "MPN" "SI7613DN-T1-GE3"
			(at 113.03 40.64 90)
			(effects
				(font
					(size 1.27 1.27)
					(thickness 0.15)
				)
			)
		)
		(property "Manufacturer" "Vishay"
			(at 123.19 36.83 0)
			(effects
				(font
					(size 1.27 1.27)
					(thickness 0.15)
				)
				(justify left bottom)
				(hide yes)
			)
		)
		(property "Author" "Antmicro"
			(at 125.73 36.83 0)
			(effects
				(font
					(size 1.27 1.27)
					(thickness 0.15)
				)
				(justify left bottom)
				(hide yes)
			)
		)
		(property "License" "Apache-2.0"
			(at 128.27 36.83 0)
			(effects
				(font
					(size 1.27 1.27)
					(thickness 0.15)
				)
				(justify left bottom)
				(hide yes)
			)
		)
		(pin "4"
		)
		(pin "5"
		)
		(pin "3"
		)
		(pin "2"
		)
		(pin "1"
		)
		(instances
			(project "data-center-rdimm-ddr5-tester"
				(path ""
					(reference "Q12")
					(unit 1)
				)
			)
		)
	)
	(symbol
		(lib_id "antmicroTransistorsFETsMOSFETsSingle:SI7613DN-T1-GE3")
		(at 335.28 86.36 270)
		(mirror x)
		(unit 1)
		(exclude_from_sim no)
		(in_bom yes)
		(on_board yes)
		(dnp no)
		(property "Reference" "Q29"
			(at 337.82 72.39 90)
			(effects
				(font
					(size 1.27 1.27)
					(thickness 0.15)
				)
			)
		)
		(property "Value" "SI7613DN-T1-GE3"
			(at 337.82 71.12 0)
			(effects
				(font
					(size 1.27 1.27)
					(thickness 0.15)
				)
				(justify left bottom)
				(hide yes)
			)
		)
		(property "Footprint" "antmicro-footprints:Vishay_PowerPAK_1212-8_Single"
			(at 336.55 71.12 0)
			(effects
				(font
					(size 1.27 1.27)
					(thickness 0.15)
				)
				(justify left bottom)
				(hide yes)
			)
		)
		(property "Datasheet" "https://www.vishay.com/docs/64809/si7613dn.pdf"
			(at 334.01 71.12 0)
			(effects
				(font
					(size 1.27 1.27)
					(thickness 0.15)
				)
				(justify left bottom)
				(hide yes)
			)
		)
		(property "Description" ""
			(at 335.28 86.36 0)
			(effects
				(font
					(size 1.27 1.27)
				)
				(hide yes)
			)
		)
		(property "MPN" "SI7613DN-T1-GE3"
			(at 337.82 74.93 90)
			(effects
				(font
					(size 1.27 1.27)
					(thickness 0.15)
				)
			)
		)
		(property "Manufacturer" "Vishay"
			(at 327.66 71.12 0)
			(effects
				(font
					(size 1.27 1.27)
					(thickness 0.15)
				)
				(justify left bottom)
				(hide yes)
			)
		)
		(property "Author" "Antmicro"
			(at 325.12 71.12 0)
			(effects
				(font
					(size 1.27 1.27)
					(thickness 0.15)
				)
				(justify left bottom)
				(hide yes)
			)
		)
		(property "License" "Apache-2.0"
			(at 322.58 71.12 0)
			(effects
				(font
					(size 1.27 1.27)
					(thickness 0.15)
				)
				(justify left bottom)
				(hide yes)
			)
		)
		(pin "4"
		)
		(pin "5"
		)
		(pin "3"
		)
		(pin "2"
		)
		(pin "1"
		)
		(instances
			(project "data-center-rdimm-ddr5-tester"
				(path ""
					(reference "Q29")
					(unit 1)
				)
			)
		)
	)
	(symbol
		(lib_id "antmicropower:GND")
		(at 314.96 57.15 0)
		(unit 1)
		(exclude_from_sim no)
		(in_bom yes)
		(on_board yes)
		(dnp no)
		(fields_autoplaced yes)
		(property "Reference" "#PWR0350"
			(at 314.96 63.5 0)
			(effects
				(font
					(size 1.27 1.27)
				)
				(hide yes)
			)
		)
		(property "Value" "GND"
			(at 313.055 61.595 0)
			(effects
				(font
					(size 1.27 1.27)
					(thickness 0.15)
				)
				(justify left bottom)
			)
		)
		(property "Footprint" ""
			(at 323.85 64.77 0)
			(effects
				(font
					(size 1.27 1.27)
					(thickness 0.15)
				)
				(justify left bottom)
				(hide yes)
			)
		)
		(property "Datasheet" ""
			(at 323.85 69.85 0)
			(effects
				(font
					(size 1.27 1.27)
					(thickness 0.15)
				)
				(justify left bottom)
				(hide yes)
			)
		)
		(property "Description" ""
			(at 314.96 57.15 0)
			(effects
				(font
					(size 1.27 1.27)
				)
				(hide yes)
			)
		)
		(property "Author" "Antmicro"
			(at 323.85 62.23 0)
			(effects
				(font
					(size 1.27 1.27)
					(thickness 0.15)
				)
				(justify left bottom)
				(hide yes)
			)
		)
		(property "License" "Apache-2.0"
			(at 323.85 64.77 0)
			(effects
				(font
					(size 1.27 1.27)
					(thickness 0.15)
				)
				(justify left bottom)
				(hide yes)
			)
		)
		(pin "1"
		)
		(instances
			(project "data-center-rdimm-ddr5-tester"
				(path ""
					(reference "#PWR0350")
					(unit 1)
				)
			)
		)
	)
	(symbol
		(lib_id "antmicroDataAcquisitionDigitaltoAnalogConvertersDAC:MCP4726A0T_DFN")
		(at 205.74 93.98 0)
		(unit 1)
		(exclude_from_sim no)
		(in_bom yes)
		(on_board yes)
		(dnp no)
		(fields_autoplaced yes)
		(property "Reference" "U12"
			(at 215.265 87.755 0)
			(effects
				(font
					(size 1.27 1.27)
					(thickness 0.15)
				)
			)
		)
		(property "Value" "MCP4726A0T_DFN"
			(at 238.76 101.6 0)
			(effects
				(font
					(size 1.27 1.27)
					(thickness 0.15)
				)
				(justify left bottom)
				(hide yes)
			)
		)
		(property "Footprint" "antmicro-footprints:DFN-6-1EP_2x2mm_P0.65mm_EP1x1.6mm"
			(at 238.76 104.14 0)
			(effects
				(font
					(size 1.27 1.27)
					(thickness 0.15)
				)
				(justify left bottom)
				(hide yes)
			)
		)
		(property "Datasheet" "https://ww1.microchip.com/downloads/en/DeviceDoc/22272C.pdf"
			(at 238.76 106.68 0)
			(effects
				(font
					(size 1.27 1.27)
					(thickness 0.15)
				)
				(justify left bottom)
				(hide yes)
			)
		)
		(property "Description" ""
			(at 205.74 93.98 0)
			(effects
				(font
					(size 1.27 1.27)
				)
			)
		)
		(property "MPN" "MCP4726A0T-E/MAY"
			(at 215.265 90.2787 0)
			(effects
				(font
					(size 1.27 1.27)
					(thickness 0.15)
				)
			)
		)
		(property "Manufacturer" "Microchip Technology"
			(at 238.76 109.22 0)
			(effects
				(font
					(size 1.27 1.27)
					(thickness 0.15)
				)
				(justify left bottom)
				(hide yes)
			)
		)
		(property "Author" "Antmicro"
			(at 238.76 111.76 0)
			(effects
				(font
					(size 1.27 1.27)
					(thickness 0.15)
				)
				(justify left bottom)
				(hide yes)
			)
		)
		(property "License" "Apache-2.0"
			(at 238.76 114.3 0)
			(effects
				(font
					(size 1.27 1.27)
					(thickness 0.15)
				)
				(justify left bottom)
				(hide yes)
			)
		)
		(pin "1"
		)
		(pin "2"
		)
		(pin "3"
		)
		(pin "4"
		)
		(pin "5"
		)
		(pin "6"
		)
		(pin "7"
		)
		(instances
			(project "data-center-rdimm-ddr5-tester"
				(path ""
					(reference "U12")
					(unit 1)
				)
			)
		)
	)
	(symbol
		(lib_id "antmicropower:+3V3_AON")
		(at 284.48 260.35 0)
		(unit 1)
		(exclude_from_sim no)
		(in_bom yes)
		(on_board yes)
		(dnp no)
		(property "Reference" "#PWR0396"
			(at 284.48 264.16 0)
			(effects
				(font
					(size 1.27 1.27)
				)
				(hide yes)
			)
		)
		(property "Value" "+3V3_AON"
			(at 284.48 256.54 0)
			(effects
				(font
					(size 1.27 1.27)
				)
			)
		)
		(property "Footprint" ""
			(at 284.48 260.35 0)
			(effects
				(font
					(size 1.27 1.27)
				)
				(hide yes)
			)
		)
		(property "Datasheet" ""
			(at 284.48 260.35 0)
			(effects
				(font
					(size 1.27 1.27)
				)
				(hide yes)
			)
		)
		(property "Description" ""
			(at 284.48 260.35 0)
			(effects
				(font
					(size 1.27 1.27)
				)
				(hide yes)
			)
		)
		(pin "1"
		)
		(instances
			(project "data-center-rdimm-ddr5-tester"
				(path ""
					(reference "#PWR0396")
					(unit 1)
				)
			)
		)
	)
	(symbol
		(lib_id "antmicropower:+1V1")
		(at 233.68 95.25 0)
		(unit 1)
		(exclude_from_sim no)
		(in_bom yes)
		(on_board yes)
		(dnp no)
		(fields_autoplaced yes)
		(property "Reference" "#PWR0562"
			(at 233.68 99.06 0)
			(effects
				(font
					(size 1.27 1.27)
				)
				(hide yes)
			)
		)
		(property "Value" "VDDQ"
			(at 233.68 91.694 0)
			(effects
				(font
					(size 1.27 1.27)
				)
			)
		)
		(property "Footprint" ""
			(at 233.68 95.25 0)
			(effects
				(font
					(size 1.27 1.27)
				)
				(hide yes)
			)
		)
		(property "Datasheet" ""
			(at 233.68 95.25 0)
			(effects
				(font
					(size 1.27 1.27)
				)
				(hide yes)
			)
		)
		(property "Description" ""
			(at 233.68 95.25 0)
			(effects
				(font
					(size 1.27 1.27)
				)
				(hide yes)
			)
		)
		(pin "1"
		)
		(instances
			(project "data-center-rdimm-ddr5-tester"
				(path ""
					(reference "#PWR0562")
					(unit 1)
				)
			)
		)
	)
	(symbol
		(lib_id "antmicroCapacitors0402:C_100n_0402")
		(at 262.89 175.26 90)
		(unit 1)
		(exclude_from_sim no)
		(in_bom yes)
		(on_board yes)
		(dnp no)
		(fields_autoplaced yes)
		(property "Reference" "C212"
			(at 265.43 171.4435 90)
			(effects
				(font
					(size 1.27 1.27)
				)
				(justify right)
			)
		)
		(property "Value" "C_100n_0402"
			(at 273.05 154.94 0)
			(effects
				(font
					(size 1.27 1.27)
					(thickness 0.15)
				)
				(justify left bottom)
				(hide yes)
			)
		)
		(property "Footprint" "antmicro-footprints:C_0402_1005Metric"
			(at 275.59 154.94 0)
			(effects
				(font
					(size 1.27 1.27)
					(thickness 0.15)
				)
				(justify left bottom)
				(hide yes)
			)
		)
		(property "Datasheet" "https://www.murata.com/products/productdetail?partno=GRM155R61H104KE14%23"
			(at 278.13 154.94 0)
			(effects
				(font
					(size 1.27 1.27)
					(thickness 0.15)
				)
				(justify left bottom)
				(hide yes)
			)
		)
		(property "Description" ""
			(at 262.89 175.26 0)
			(effects
				(font
					(size 1.27 1.27)
				)
				(hide yes)
			)
		)
		(property "Manufacturer" "Murata"
			(at 283.21 154.94 0)
			(effects
				(font
					(size 1.27 1.27)
					(thickness 0.15)
				)
				(justify left bottom)
				(hide yes)
			)
		)
		(property "MPN" "GRM155R61H104KE14D"
			(at 280.67 154.94 0)
			(effects
				(font
					(size 1.27 1.27)
					(thickness 0.15)
				)
				(justify left bottom)
				(hide yes)
			)
		)
		(property "Val" "100n"
			(at 265.43 173.9835 90)
			(effects
				(font
					(size 1.27 1.27)
					(thickness 0.15)
				)
				(justify right)
			)
		)
		(property "License" "Apache-2.0"
			(at 285.75 154.94 0)
			(effects
				(font
					(size 1.27 1.27)
					(thickness 0.15)
				)
				(justify left bottom)
				(hide yes)
			)
		)
		(property "Author" "Antmicro"
			(at 288.29 154.94 0)
			(effects
				(font
					(size 1.27 1.27)
					(thickness 0.15)
				)
				(justify left bottom)
				(hide yes)
			)
		)
		(property "Voltage" "50V"
			(at 290.83 154.94 0)
			(effects
				(font
					(size 1.27 1.27)
				)
				(justify left bottom)
				(hide yes)
			)
		)
		(property "Dielectric" "X5R"
			(at 293.37 154.94 0)
			(effects
				(font
					(size 1.27 1.27)
				)
				(justify left bottom)
				(hide yes)
			)
		)
		(pin "1"
		)
		(pin "2"
		)
		(instances
			(project "data-center-rdimm-ddr5-tester"
				(path ""
					(reference "C212")
					(unit 1)
				)
			)
		)
	)
	(symbol
		(lib_id "antmicroCapacitors0402:C_100n_0402")
		(at 77.47 95.25 90)
		(unit 1)
		(exclude_from_sim no)
		(in_bom yes)
		(on_board yes)
		(dnp no)
		(fields_autoplaced yes)
		(property "Reference" "C176"
			(at 80.01 91.4335 90)
			(effects
				(font
					(size 1.27 1.27)
				)
				(justify right)
			)
		)
		(property "Value" "C_100n_0402"
			(at 87.63 74.93 0)
			(effects
				(font
					(size 1.27 1.27)
					(thickness 0.15)
				)
				(justify left bottom)
				(hide yes)
			)
		)
		(property "Footprint" "antmicro-footprints:C_0402_1005Metric"
			(at 90.17 74.93 0)
			(effects
				(font
					(size 1.27 1.27)
					(thickness 0.15)
				)
				(justify left bottom)
				(hide yes)
			)
		)
		(property "Datasheet" "https://www.murata.com/products/productdetail?partno=GRM155R61H104KE14%23"
			(at 92.71 74.93 0)
			(effects
				(font
					(size 1.27 1.27)
					(thickness 0.15)
				)
				(justify left bottom)
				(hide yes)
			)
		)
		(property "Description" ""
			(at 77.47 95.25 0)
			(effects
				(font
					(size 1.27 1.27)
				)
				(hide yes)
			)
		)
		(property "Manufacturer" "Murata"
			(at 97.79 74.93 0)
			(effects
				(font
					(size 1.27 1.27)
					(thickness 0.15)
				)
				(justify left bottom)
				(hide yes)
			)
		)
		(property "MPN" "GRM155R61H104KE14D"
			(at 95.25 74.93 0)
			(effects
				(font
					(size 1.27 1.27)
					(thickness 0.15)
				)
				(justify left bottom)
				(hide yes)
			)
		)
		(property "Val" "100n"
			(at 80.01 93.9735 90)
			(effects
				(font
					(size 1.27 1.27)
					(thickness 0.15)
				)
				(justify right)
			)
		)
		(property "License" "Apache-2.0"
			(at 100.33 74.93 0)
			(effects
				(font
					(size 1.27 1.27)
					(thickness 0.15)
				)
				(justify left bottom)
				(hide yes)
			)
		)
		(property "Author" "Antmicro"
			(at 102.87 74.93 0)
			(effects
				(font
					(size 1.27 1.27)
					(thickness 0.15)
				)
				(justify left bottom)
				(hide yes)
			)
		)
		(property "Voltage" "50V"
			(at 105.41 74.93 0)
			(effects
				(font
					(size 1.27 1.27)
				)
				(justify left bottom)
				(hide yes)
			)
		)
		(property "Dielectric" "X5R"
			(at 107.95 74.93 0)
			(effects
				(font
					(size 1.27 1.27)
				)
				(justify left bottom)
				(hide yes)
			)
		)
		(pin "1"
		)
		(pin "2"
		)
		(instances
			(project "data-center-rdimm-ddr5-tester"
				(path ""
					(reference "C176")
					(unit 1)
				)
			)
		)
	)
	(symbol
		(lib_name "ESDA25P35-1U1M_1")
		(lib_id "antmicroTVSDiodes:ESDA25P35-1U1M")
		(at 69.85 49.53 270)
		(unit 1)
		(exclude_from_sim no)
		(in_bom yes)
		(on_board yes)
		(dnp no)
		(property "Reference" "D16"
			(at 68.58 46.99 0)
			(effects
				(font
					(size 1.27 1.27)
					(thickness 0.15)
				)
				(justify left)
			)
		)
		(property "Value" "ESDA25P35-1U1M"
			(at 54.61 73.66 0)
			(effects
				(font
					(size 1.27 1.27)
					(thickness 0.15)
				)
				(justify left bottom)
				(hide yes)
			)
		)
		(property "Footprint" "antmicro-footprints:QFN-2L_1.6x1x0.55mm"
			(at 59.69 73.66 0)
			(effects
				(font
					(size 1.27 1.27)
					(thickness 0.15)
				)
				(justify left bottom)
				(hide yes)
			)
		)
		(property "Datasheet" "https://www.st.com/resource/en/datasheet/esda25p35-1u1m.pdf"
			(at 57.15 73.66 0)
			(effects
				(font
					(size 1.27 1.27)
					(thickness 0.15)
				)
				(justify left bottom)
				(hide yes)
			)
		)
		(property "Description" ""
			(at 69.85 49.53 0)
			(effects
				(font
					(size 1.27 1.27)
				)
				(hide yes)
			)
		)
		(property "MPN" "ESDA25P35-1U1M"
			(at 52.07 55.88 90)
			(effects
				(font
					(size 1.27 1.27)
					(thickness 0.15)
				)
				(justify left)
			)
		)
		(property "Manufacturer" "STMicroelectronics"
			(at 52.07 73.66 0)
			(effects
				(font
					(size 1.27 1.27)
					(thickness 0.15)
				)
				(justify left bottom)
				(hide yes)
			)
		)
		(property "Author" "Antmicro"
			(at 49.53 73.66 0)
			(effects
				(font
					(size 1.27 1.27)
					(thickness 0.15)
				)
				(justify left bottom)
				(hide yes)
			)
		)
		(property "License" "Apache-2.0"
			(at 46.99 73.66 0)
			(effects
				(font
					(size 1.27 1.27)
					(thickness 0.15)
				)
				(justify left bottom)
				(hide yes)
			)
		)
		(pin "1"
		)
		(pin "2"
		)
		(instances
			(project "data-center-rdimm-ddr5-tester"
				(path ""
					(reference "D16")
					(unit 1)
				)
			)
		)
	)
	(symbol
		(lib_id "antmicropower:+3V3_AON")
		(at 238.76 33.02 0)
		(unit 1)
		(exclude_from_sim no)
		(in_bom yes)
		(on_board yes)
		(dnp no)
		(property "Reference" "#PWR0314"
			(at 238.76 36.83 0)
			(effects
				(font
					(size 1.27 1.27)
				)
				(hide yes)
			)
		)
		(property "Value" "+3V3_AON"
			(at 238.76 29.21 0)
			(effects
				(font
					(size 1.27 1.27)
				)
			)
		)
		(property "Footprint" ""
			(at 238.76 33.02 0)
			(effects
				(font
					(size 1.27 1.27)
				)
				(hide yes)
			)
		)
		(property "Datasheet" ""
			(at 238.76 33.02 0)
			(effects
				(font
					(size 1.27 1.27)
				)
				(hide yes)
			)
		)
		(property "Description" ""
			(at 238.76 33.02 0)
			(effects
				(font
					(size 1.27 1.27)
				)
				(hide yes)
			)
		)
		(pin "1"
		)
		(instances
			(project "data-center-rdimm-ddr5-tester"
				(path ""
					(reference "#PWR0314")
					(unit 1)
				)
			)
		)
	)
	(symbol
		(lib_id "antmicroCapacitors0402:C_100n_0402")
		(at 359.41 102.87 90)
		(unit 1)
		(exclude_from_sim no)
		(in_bom yes)
		(on_board yes)
		(dnp no)
		(fields_autoplaced yes)
		(property "Reference" "C321"
			(at 362.585 99.0535 90)
			(effects
				(font
					(size 1.27 1.27)
					(thickness 0.15)
				)
				(justify right)
			)
		)
		(property "Value" "C_100n_0402"
			(at 369.57 82.55 0)
			(effects
				(font
					(size 1.27 1.27)
					(thickness 0.15)
				)
				(justify left bottom)
				(hide yes)
			)
		)
		(property "Footprint" "antmicro-footprints:C_0402_1005Metric"
			(at 372.11 82.55 0)
			(effects
				(font
					(size 1.27 1.27)
					(thickness 0.15)
				)
				(justify left bottom)
				(hide yes)
			)
		)
		(property "Datasheet" "https://www.murata.com/products/productdetail?partno=GRM155R61H104KE14%23"
			(at 374.65 82.55 0)
			(effects
				(font
					(size 1.27 1.27)
					(thickness 0.15)
				)
				(justify left bottom)
				(hide yes)
			)
		)
		(property "Description" ""
			(at 359.41 102.87 0)
			(effects
				(font
					(size 1.27 1.27)
				)
				(hide yes)
			)
		)
		(property "MPN" "GRM155R61H104KE14D"
			(at 377.19 82.55 0)
			(effects
				(font
					(size 1.27 1.27)
					(thickness 0.15)
				)
				(justify left bottom)
				(hide yes)
			)
		)
		(property "Manufacturer" "Murata"
			(at 379.73 82.55 0)
			(effects
				(font
					(size 1.27 1.27)
					(thickness 0.15)
				)
				(justify left bottom)
				(hide yes)
			)
		)
		(property "License" "Apache-2.0"
			(at 382.27 82.55 0)
			(effects
				(font
					(size 1.27 1.27)
					(thickness 0.15)
				)
				(justify left bottom)
				(hide yes)
			)
		)
		(property "Author" "Antmicro"
			(at 384.81 82.55 0)
			(effects
				(font
					(size 1.27 1.27)
					(thickness 0.15)
				)
				(justify left bottom)
				(hide yes)
			)
		)
		(property "Val" "100n"
			(at 362.585 101.5935 90)
			(effects
				(font
					(size 1.27 1.27)
					(thickness 0.15)
				)
				(justify right)
			)
		)
		(property "Voltage" "50V"
			(at 387.35 82.55 0)
			(effects
				(font
					(size 1.27 1.27)
				)
				(justify left bottom)
				(hide yes)
			)
		)
		(property "Dielectric" "X5R"
			(at 389.89 82.55 0)
			(effects
				(font
					(size 1.27 1.27)
				)
				(justify left bottom)
				(hide yes)
			)
		)
		(pin "1"
		)
		(pin "2"
		)
		(instances
			(project "data-center-rdimm-ddr5-tester"
				(path ""
					(reference "C321")
					(unit 1)
				)
			)
		)
	)
	(symbol
		(lib_id "antmicroWire2BoardConnectors:JST_SH_1x2_BM02B-SRSS-TB-LF-SN")
		(at 365.76 78.74 0)
		(unit 1)
		(exclude_from_sim no)
		(in_bom yes)
		(on_board yes)
		(dnp no)
		(fields_autoplaced yes)
		(property "Reference" "J17"
			(at 372.745 80.01 0)
			(effects
				(font
					(size 1.27 1.27)
					(thickness 0.15)
				)
				(justify left)
			)
		)
		(property "Value" "JST_SH_1x2_BM02B-SRSS-TB-LF-SN"
			(at 384.81 86.36 0)
			(effects
				(font
					(size 1.27 1.27)
					(thickness 0.15)
				)
				(justify left bottom)
				(hide yes)
			)
		)
		(property "Footprint" "antmicro-footprints:Conn_JST_SH_1x2_BM02B-SRSS-TB-LF-SN"
			(at 384.81 88.9 0)
			(effects
				(font
					(size 1.27 1.27)
					(thickness 0.15)
				)
				(justify left bottom)
				(hide yes)
			)
		)
		(property "Datasheet" "https://www.jst-mfg.com/product/pdf/eng/eSH.pdf"
			(at 384.81 91.44 0)
			(effects
				(font
					(size 1.27 1.27)
					(thickness 0.15)
				)
				(justify left bottom)
				(hide yes)
			)
		)
		(property "Description" ""
			(at 365.76 78.74 0)
			(effects
				(font
					(size 1.27 1.27)
				)
				(hide yes)
			)
		)
		(property "MPN" "BM02B-SRSS-TB(LF)(SN)"
			(at 372.745 82.55 0)
			(effects
				(font
					(size 1.27 1.27)
					(thickness 0.15)
				)
				(justify left)
			)
		)
		(property "Manufacturer" "JST Automotive Connectors"
			(at 384.81 93.98 0)
			(effects
				(font
					(size 1.27 1.27)
					(thickness 0.15)
				)
				(justify left bottom)
				(hide yes)
			)
		)
		(property "Author" "Antmicro"
			(at 384.81 96.52 0)
			(effects
				(font
					(size 1.27 1.27)
					(thickness 0.15)
				)
				(justify left bottom)
				(hide yes)
			)
		)
		(property "License" "Apache-2.0"
			(at 384.81 99.06 0)
			(effects
				(font
					(size 1.27 1.27)
					(thickness 0.15)
				)
				(justify left bottom)
				(hide yes)
			)
		)
		(pin "2"
		)
		(pin "MP"
		)
		(pin "1"
		)
		(instances
			(project "data-center-rdimm-ddr5-tester"
				(path ""
					(reference "J17")
					(unit 1)
				)
			)
		)
	)
	(symbol
		(lib_id "antmicroResistors0402:R_47k_0402")
		(at 60.96 220.98 90)
		(unit 1)
		(exclude_from_sim no)
		(in_bom yes)
		(on_board yes)
		(dnp no)
		(fields_autoplaced yes)
		(property "Reference" "R139"
			(at 59.309 217.6094 90)
			(effects
				(font
					(size 1.27 1.27)
				)
				(justify left)
			)
		)
		(property "Value" "R_47k_0402"
			(at 73.66 200.66 0)
			(effects
				(font
					(size 1.27 1.27)
					(thickness 0.15)
				)
				(justify left bottom)
				(hide yes)
			)
		)
		(property "Footprint" "antmicro-footprints:R_0402_1005Metric"
			(at 76.2 200.66 0)
			(effects
				(font
					(size 1.27 1.27)
					(thickness 0.15)
				)
				(justify left bottom)
				(hide yes)
			)
		)
		(property "Datasheet" "https://www.bourns.com/docs/product-datasheets/cr.pdf"
			(at 78.74 200.66 0)
			(effects
				(font
					(size 1.27 1.27)
					(thickness 0.15)
				)
				(justify left bottom)
				(hide yes)
			)
		)
		(property "Description" ""
			(at 60.96 220.98 0)
			(effects
				(font
					(size 1.27 1.27)
				)
				(hide yes)
			)
		)
		(property "Manufacturer" "Bourns"
			(at 83.82 200.66 0)
			(effects
				(font
					(size 1.27 1.27)
					(thickness 0.15)
				)
				(justify left bottom)
				(hide yes)
			)
		)
		(property "MPN" "CR0402-FX-4702GLF"
			(at 81.28 200.66 0)
			(effects
				(font
					(size 1.27 1.27)
					(thickness 0.15)
				)
				(justify left bottom)
				(hide yes)
			)
		)
		(property "Val" "47k"
			(at 59.309 220.1397 90)
			(effects
				(font
					(size 1.27 1.27)
					(thickness 0.15)
				)
				(justify left)
			)
		)
		(property "License" "Apache-2.0"
			(at 86.36 200.66 0)
			(effects
				(font
					(size 1.27 1.27)
					(thickness 0.15)
				)
				(justify left bottom)
				(hide yes)
			)
		)
		(property "Author" "Antmicro"
			(at 88.9 200.66 0)
			(effects
				(font
					(size 1.27 1.27)
					(thickness 0.15)
				)
				(justify left bottom)
				(hide yes)
			)
		)
		(property "Tolerance" "1%"
			(at 71.12 200.66 0)
			(effects
				(font
					(size 1.27 1.27)
				)
				(justify left bottom)
				(hide yes)
			)
		)
		(pin "1"
		)
		(pin "2"
		)
		(instances
			(project "data-center-rdimm-ddr5-tester"
				(path ""
					(reference "R139")
					(unit 1)
				)
			)
		)
	)
	(symbol
		(lib_id "antmicropower:GND")
		(at 229.87 194.31 0)
		(unit 1)
		(exclude_from_sim no)
		(in_bom yes)
		(on_board yes)
		(dnp no)
		(fields_autoplaced yes)
		(property "Reference" "#PWR0377"
			(at 229.87 200.66 0)
			(effects
				(font
					(size 1.27 1.27)
				)
				(hide yes)
			)
		)
		(property "Value" "GND"
			(at 227.965 198.755 0)
			(effects
				(font
					(size 1.27 1.27)
					(thickness 0.15)
				)
				(justify left bottom)
			)
		)
		(property "Footprint" ""
			(at 238.76 201.93 0)
			(effects
				(font
					(size 1.27 1.27)
					(thickness 0.15)
				)
				(justify left bottom)
				(hide yes)
			)
		)
		(property "Datasheet" ""
			(at 238.76 207.01 0)
			(effects
				(font
					(size 1.27 1.27)
					(thickness 0.15)
				)
				(justify left bottom)
				(hide yes)
			)
		)
		(property "Description" ""
			(at 229.87 194.31 0)
			(effects
				(font
					(size 1.27 1.27)
				)
				(hide yes)
			)
		)
		(property "Author" "Antmicro"
			(at 238.76 199.39 0)
			(effects
				(font
					(size 1.27 1.27)
					(thickness 0.15)
				)
				(justify left bottom)
				(hide yes)
			)
		)
		(property "License" "Apache-2.0"
			(at 238.76 201.93 0)
			(effects
				(font
					(size 1.27 1.27)
					(thickness 0.15)
				)
				(justify left bottom)
				(hide yes)
			)
		)
		(pin "1"
		)
		(instances
			(project "data-center-rdimm-ddr5-tester"
				(path ""
					(reference "#PWR0377")
					(unit 1)
				)
			)
		)
	)
	(symbol
		(lib_id "antmicropower:GND")
		(at 72.39 180.34 0)
		(unit 1)
		(exclude_from_sim no)
		(in_bom yes)
		(on_board yes)
		(dnp no)
		(fields_autoplaced yes)
		(property "Reference" "#PWR0318"
			(at 72.39 186.69 0)
			(effects
				(font
					(size 1.27 1.27)
				)
				(hide yes)
			)
		)
		(property "Value" "GND"
			(at 70.485 184.785 0)
			(effects
				(font
					(size 1.27 1.27)
					(thickness 0.15)
				)
				(justify left bottom)
			)
		)
		(property "Footprint" ""
			(at 81.28 187.96 0)
			(effects
				(font
					(size 1.27 1.27)
					(thickness 0.15)
				)
				(justify left bottom)
				(hide yes)
			)
		)
		(property "Datasheet" ""
			(at 81.28 193.04 0)
			(effects
				(font
					(size 1.27 1.27)
					(thickness 0.15)
				)
				(justify left bottom)
				(hide yes)
			)
		)
		(property "Description" ""
			(at 72.39 180.34 0)
			(effects
				(font
					(size 1.27 1.27)
				)
				(hide yes)
			)
		)
		(property "Author" "Antmicro"
			(at 81.28 185.42 0)
			(effects
				(font
					(size 1.27 1.27)
					(thickness 0.15)
				)
				(justify left bottom)
				(hide yes)
			)
		)
		(property "License" "Apache-2.0"
			(at 81.28 187.96 0)
			(effects
				(font
					(size 1.27 1.27)
					(thickness 0.15)
				)
				(justify left bottom)
				(hide yes)
			)
		)
		(pin "1"
		)
		(instances
			(project "data-center-rdimm-ddr5-tester"
				(path ""
					(reference "#PWR0318")
					(unit 1)
				)
			)
		)
	)
	(symbol
		(lib_id "antmicropower:GND")
		(at 39.37 180.34 0)
		(unit 1)
		(exclude_from_sim no)
		(in_bom yes)
		(on_board yes)
		(dnp no)
		(fields_autoplaced yes)
		(property "Reference" "#PWR0341"
			(at 39.37 186.69 0)
			(effects
				(font
					(size 1.27 1.27)
				)
				(hide yes)
			)
		)
		(property "Value" "GND"
			(at 37.465 184.785 0)
			(effects
				(font
					(size 1.27 1.27)
					(thickness 0.15)
				)
				(justify left bottom)
			)
		)
		(property "Footprint" ""
			(at 48.26 187.96 0)
			(effects
				(font
					(size 1.27 1.27)
					(thickness 0.15)
				)
				(justify left bottom)
				(hide yes)
			)
		)
		(property "Datasheet" ""
			(at 48.26 193.04 0)
			(effects
				(font
					(size 1.27 1.27)
					(thickness 0.15)
				)
				(justify left bottom)
				(hide yes)
			)
		)
		(property "Description" ""
			(at 39.37 180.34 0)
			(effects
				(font
					(size 1.27 1.27)
				)
				(hide yes)
			)
		)
		(property "Author" "Antmicro"
			(at 48.26 185.42 0)
			(effects
				(font
					(size 1.27 1.27)
					(thickness 0.15)
				)
				(justify left bottom)
				(hide yes)
			)
		)
		(property "License" "Apache-2.0"
			(at 48.26 187.96 0)
			(effects
				(font
					(size 1.27 1.27)
					(thickness 0.15)
				)
				(justify left bottom)
				(hide yes)
			)
		)
		(pin "1"
		)
		(instances
			(project "data-center-rdimm-ddr5-tester"
				(path ""
					(reference "#PWR0341")
					(unit 1)
				)
			)
		)
	)
	(symbol
		(lib_id "antmicroTransistorsFETsMOSFETsSingle:SI7613DN-T1-GE3")
		(at 115.57 85.09 90)
		(unit 1)
		(exclude_from_sim no)
		(in_bom yes)
		(on_board yes)
		(dnp no)
		(fields_autoplaced yes)
		(property "Reference" "Q13"
			(at 113.03 71.12 90)
			(effects
				(font
					(size 1.27 1.27)
					(thickness 0.15)
				)
			)
		)
		(property "Value" "SI7613DN-T1-GE3"
			(at 113.03 69.85 0)
			(effects
				(font
					(size 1.27 1.27)
					(thickness 0.15)
				)
				(justify left bottom)
				(hide yes)
			)
		)
		(property "Footprint" "antmicro-footprints:Vishay_PowerPAK_1212-8_Single"
			(at 114.3 69.85 0)
			(effects
				(font
					(size 1.27 1.27)
					(thickness 0.15)
				)
				(justify left bottom)
				(hide yes)
			)
		)
		(property "Datasheet" "https://www.vishay.com/docs/64809/si7613dn.pdf"
			(at 116.84 69.85 0)
			(effects
				(font
					(size 1.27 1.27)
					(thickness 0.15)
				)
				(justify left bottom)
				(hide yes)
			)
		)
		(property "Description" ""
			(at 115.57 85.09 0)
			(effects
				(font
					(size 1.27 1.27)
				)
				(hide yes)
			)
		)
		(property "MPN" "SI7613DN-T1-GE3"
			(at 113.03 73.66 90)
			(effects
				(font
					(size 1.27 1.27)
					(thickness 0.15)
				)
			)
		)
		(property "Manufacturer" "Vishay"
			(at 123.19 69.85 0)
			(effects
				(font
					(size 1.27 1.27)
					(thickness 0.15)
				)
				(justify left bottom)
				(hide yes)
			)
		)
		(property "Author" "Antmicro"
			(at 125.73 69.85 0)
			(effects
				(font
					(size 1.27 1.27)
					(thickness 0.15)
				)
				(justify left bottom)
				(hide yes)
			)
		)
		(property "License" "Apache-2.0"
			(at 128.27 69.85 0)
			(effects
				(font
					(size 1.27 1.27)
					(thickness 0.15)
				)
				(justify left bottom)
				(hide yes)
			)
		)
		(pin "4"
		)
		(pin "5"
		)
		(pin "3"
		)
		(pin "2"
		)
		(pin "1"
		)
		(instances
			(project "data-center-rdimm-ddr5-tester"
				(path ""
					(reference "Q13")
					(unit 1)
				)
			)
		)
	)
	(symbol
		(lib_id "antmicropower:VDC")
		(at 189.23 33.02 0)
		(unit 1)
		(exclude_from_sim no)
		(in_bom yes)
		(on_board yes)
		(dnp no)
		(property "Reference" "#PWR0301"
			(at 189.23 35.56 0)
			(effects
				(font
					(size 1.27 1.27)
				)
				(hide yes)
			)
		)
		(property "Value" "VDC"
			(at 189.23 29.21 0)
			(effects
				(font
					(size 1.27 1.27)
				)
			)
		)
		(property "Footprint" ""
			(at 189.23 33.02 0)
			(effects
				(font
					(size 1.27 1.27)
				)
				(hide yes)
			)
		)
		(property "Datasheet" ""
			(at 189.23 33.02 0)
			(effects
				(font
					(size 1.27 1.27)
				)
				(hide yes)
			)
		)
		(property "Description" ""
			(at 189.23 33.02 0)
			(effects
				(font
					(size 1.27 1.27)
				)
				(hide yes)
			)
		)
		(pin "1"
		)
		(instances
			(project "data-center-rdimm-ddr5-tester"
				(path ""
					(reference "#PWR0301")
					(unit 1)
				)
			)
		)
	)
	(symbol
		(lib_id "antmicropower:+3V3")
		(at 115.57 231.14 0)
		(unit 1)
		(exclude_from_sim no)
		(in_bom yes)
		(on_board yes)
		(dnp no)
		(fields_autoplaced yes)
		(property "Reference" "#PWR0508"
			(at 130.81 231.14 0)
			(effects
				(font
					(size 1.27 1.27)
					(thickness 0.15)
				)
				(justify left bottom)
				(hide yes)
			)
		)
		(property "Value" "+3V3"
			(at 115.57 226.06 0)
			(effects
				(font
					(size 1.27 1.27)
					(thickness 0.15)
				)
			)
		)
		(property "Footprint" ""
			(at 130.81 238.76 0)
			(effects
				(font
					(size 1.27 1.27)
					(thickness 0.15)
				)
				(justify left bottom)
				(hide yes)
			)
		)
		(property "Datasheet" ""
			(at 130.81 241.3 0)
			(effects
				(font
					(size 1.27 1.27)
					(thickness 0.15)
				)
				(justify left bottom)
				(hide yes)
			)
		)
		(property "Description" ""
			(at 115.57 231.14 0)
			(effects
				(font
					(size 1.27 1.27)
				)
				(hide yes)
			)
		)
		(property "Author" "Antmicro"
			(at 130.81 233.68 0)
			(effects
				(font
					(size 1.27 1.27)
					(thickness 0.15)
				)
				(justify left bottom)
				(hide yes)
			)
		)
		(property "License" "Apache-2.0"
			(at 130.81 236.22 0)
			(effects
				(font
					(size 1.27 1.27)
					(thickness 0.15)
				)
				(justify left bottom)
				(hide yes)
			)
		)
		(pin "1"
		)
		(instances
			(project "data-center-rdimm-ddr5-tester"
				(path ""
					(reference "#PWR0508")
					(unit 1)
				)
			)
		)
	)
	(symbol
		(lib_id "antmicroCapacitors0603:C_10u_25V_0603")
		(at 316.23 86.36 90)
		(unit 1)
		(exclude_from_sim no)
		(in_bom yes)
		(on_board yes)
		(dnp no)
		(fields_autoplaced yes)
		(property "Reference" "C326"
			(at 318.77 82.5436 90)
			(effects
				(font
					(size 1.27 1.27)
					(thickness 0.15)
				)
				(justify right)
			)
		)
		(property "Value" "C_10u_25V_0603"
			(at 326.39 66.04 0)
			(effects
				(font
					(size 1.27 1.27)
					(thickness 0.15)
				)
				(justify left bottom)
				(hide yes)
			)
		)
		(property "Footprint" "antmicro-footprints:C_0603_1608Metric"
			(at 328.93 66.04 0)
			(effects
				(font
					(size 1.27 1.27)
					(thickness 0.15)
				)
				(justify left bottom)
				(hide yes)
			)
		)
		(property "Datasheet" "https://product.tdk.com/en/search/capacitor/ceramic/mlcc/info?part_no=C1608X5R1E106M080AC"
			(at 331.47 66.04 0)
			(effects
				(font
					(size 1.27 1.27)
					(thickness 0.15)
				)
				(justify left bottom)
				(hide yes)
			)
		)
		(property "Description" ""
			(at 316.23 86.36 0)
			(effects
				(font
					(size 1.27 1.27)
				)
				(hide yes)
			)
		)
		(property "MPN" "C1608X5R1E106M080AC"
			(at 334.01 66.04 0)
			(effects
				(font
					(size 1.27 1.27)
					(thickness 0.15)
				)
				(justify left bottom)
				(hide yes)
			)
		)
		(property "Manufacturer" "TDK"
			(at 336.55 66.04 0)
			(effects
				(font
					(size 1.27 1.27)
					(thickness 0.15)
				)
				(justify left bottom)
				(hide yes)
			)
		)
		(property "License" "Apache-2.0"
			(at 339.09 66.04 0)
			(effects
				(font
					(size 1.27 1.27)
					(thickness 0.15)
				)
				(justify left bottom)
				(hide yes)
			)
		)
		(property "Author" "Antmicro"
			(at 341.63 66.04 0)
			(effects
				(font
					(size 1.27 1.27)
					(thickness 0.15)
				)
				(justify left bottom)
				(hide yes)
			)
		)
		(property "Val" "10u"
			(at 318.77 85.0836 90)
			(effects
				(font
					(size 1.27 1.27)
					(thickness 0.15)
				)
				(justify right)
			)
		)
		(property "Voltage" "25V"
			(at 344.17 66.04 0)
			(effects
				(font
					(size 1.27 1.27)
				)
				(justify left bottom)
				(hide yes)
			)
		)
		(property "Dielectric" ""
			(at 346.71 66.04 0)
			(effects
				(font
					(size 1.27 1.27)
				)
				(justify left bottom)
				(hide yes)
			)
		)
		(pin "2"
		)
		(pin "1"
		)
		(instances
			(project "data-center-rdimm-ddr5-tester"
				(path ""
					(reference "C326")
					(unit 1)
				)
			)
		)
	)
	(symbol
		(lib_id "antmicroCapacitors0402:C_10u_6.3V_0402")
		(at 241.3 104.14 90)
		(unit 1)
		(exclude_from_sim no)
		(in_bom yes)
		(on_board yes)
		(dnp no)
		(property "Reference" "C331"
			(at 241.554 99.822 90)
			(effects
				(font
					(size 1.27 1.27)
					(thickness 0.15)
				)
				(justify right)
			)
		)
		(property "Value" "C_10u_6.3V_0402"
			(at 251.46 83.82 0)
			(effects
				(font
					(size 1.27 1.27)
					(thickness 0.15)
				)
				(justify left bottom)
				(hide yes)
			)
		)
		(property "Footprint" "antmicro-footprints:C_0402_1005Metric"
			(at 254 83.82 0)
			(effects
				(font
					(size 1.27 1.27)
					(thickness 0.15)
				)
				(justify left bottom)
				(hide yes)
			)
		)
		(property "Datasheet" "https://www.murata.com/products/productdetail?partno=GRM155R60J106ME15%23"
			(at 256.54 83.82 0)
			(effects
				(font
					(size 1.27 1.27)
					(thickness 0.15)
				)
				(justify left bottom)
				(hide yes)
			)
		)
		(property "Description" ""
			(at 241.3 104.14 0)
			(effects
				(font
					(size 1.27 1.27)
				)
			)
		)
		(property "MPN" "GRM155R60J106ME15D"
			(at 259.08 83.82 0)
			(effects
				(font
					(size 1.27 1.27)
					(thickness 0.15)
				)
				(justify left bottom)
				(hide yes)
			)
		)
		(property "Manufacturer" "Murata"
			(at 261.62 83.82 0)
			(effects
				(font
					(size 1.27 1.27)
					(thickness 0.15)
				)
				(justify left bottom)
				(hide yes)
			)
		)
		(property "License" "Apache-2.0"
			(at 264.16 83.82 0)
			(effects
				(font
					(size 1.27 1.27)
					(thickness 0.15)
				)
				(justify left bottom)
				(hide yes)
			)
		)
		(property "Author" "Antmicro"
			(at 266.7 83.82 0)
			(effects
				(font
					(size 1.27 1.27)
					(thickness 0.15)
				)
				(justify left bottom)
				(hide yes)
			)
		)
		(property "Val" "10u"
			(at 241.808 103.632 90)
			(effects
				(font
					(size 1.27 1.27)
					(thickness 0.15)
				)
				(justify right)
			)
		)
		(property "Voltage" "6.3V"
			(at 269.24 83.82 0)
			(effects
				(font
					(size 1.27 1.27)
				)
				(justify left bottom)
				(hide yes)
			)
		)
		(property "Dielectric" "X5R"
			(at 271.78 83.82 0)
			(effects
				(font
					(size 1.27 1.27)
				)
				(justify left bottom)
				(hide yes)
			)
		)
		(pin "1"
		)
		(pin "2"
		)
		(instances
			(project "data-center-rdimm-ddr5-tester"
				(path ""
					(reference "C331")
					(unit 1)
				)
			)
		)
	)
	(symbol
		(lib_id "antmicropower:GND")
		(at 180.34 196.85 0)
		(unit 1)
		(exclude_from_sim no)
		(in_bom yes)
		(on_board yes)
		(dnp no)
		(fields_autoplaced yes)
		(property "Reference" "#PWR0359"
			(at 180.34 203.2 0)
			(effects
				(font
					(size 1.27 1.27)
				)
				(hide yes)
			)
		)
		(property "Value" "GND"
			(at 178.435 201.295 0)
			(effects
				(font
					(size 1.27 1.27)
					(thickness 0.15)
				)
				(justify left bottom)
			)
		)
		(property "Footprint" ""
			(at 189.23 204.47 0)
			(effects
				(font
					(size 1.27 1.27)
					(thickness 0.15)
				)
				(justify left bottom)
				(hide yes)
			)
		)
		(property "Datasheet" ""
			(at 189.23 209.55 0)
			(effects
				(font
					(size 1.27 1.27)
					(thickness 0.15)
				)
				(justify left bottom)
				(hide yes)
			)
		)
		(property "Description" ""
			(at 180.34 196.85 0)
			(effects
				(font
					(size 1.27 1.27)
				)
				(hide yes)
			)
		)
		(property "Author" "Antmicro"
			(at 189.23 201.93 0)
			(effects
				(font
					(size 1.27 1.27)
					(thickness 0.15)
				)
				(justify left bottom)
				(hide yes)
			)
		)
		(property "License" "Apache-2.0"
			(at 189.23 204.47 0)
			(effects
				(font
					(size 1.27 1.27)
					(thickness 0.15)
				)
				(justify left bottom)
				(hide yes)
			)
		)
		(pin "1"
		)
		(instances
			(project "data-center-rdimm-ddr5-tester"
				(path ""
					(reference "#PWR0359")
					(unit 1)
				)
			)
		)
	)
	(symbol
		(lib_id "antmicropower:GND")
		(at 189.23 52.07 0)
		(unit 1)
		(exclude_from_sim no)
		(in_bom yes)
		(on_board yes)
		(dnp no)
		(fields_autoplaced yes)
		(property "Reference" "#PWR0302"
			(at 189.23 58.42 0)
			(effects
				(font
					(size 1.27 1.27)
				)
				(hide yes)
			)
		)
		(property "Value" "GND"
			(at 187.325 56.515 0)
			(effects
				(font
					(size 1.27 1.27)
					(thickness 0.15)
				)
				(justify left bottom)
			)
		)
		(property "Footprint" ""
			(at 198.12 59.69 0)
			(effects
				(font
					(size 1.27 1.27)
					(thickness 0.15)
				)
				(justify left bottom)
				(hide yes)
			)
		)
		(property "Datasheet" ""
			(at 198.12 64.77 0)
			(effects
				(font
					(size 1.27 1.27)
					(thickness 0.15)
				)
				(justify left bottom)
				(hide yes)
			)
		)
		(property "Description" ""
			(at 189.23 52.07 0)
			(effects
				(font
					(size 1.27 1.27)
				)
				(hide yes)
			)
		)
		(property "Author" "Antmicro"
			(at 198.12 57.15 0)
			(effects
				(font
					(size 1.27 1.27)
					(thickness 0.15)
				)
				(justify left bottom)
				(hide yes)
			)
		)
		(property "License" "Apache-2.0"
			(at 198.12 59.69 0)
			(effects
				(font
					(size 1.27 1.27)
					(thickness 0.15)
				)
				(justify left bottom)
				(hide yes)
			)
		)
		(pin "1"
		)
		(instances
			(project "data-center-rdimm-ddr5-tester"
				(path ""
					(reference "#PWR0302")
					(unit 1)
				)
			)
		)
	)
	(symbol
		(lib_id "antmicropower:GND")
		(at 52.07 180.34 0)
		(unit 1)
		(exclude_from_sim no)
		(in_bom yes)
		(on_board yes)
		(dnp no)
		(fields_autoplaced yes)
		(property "Reference" "#PWR0343"
			(at 52.07 186.69 0)
			(effects
				(font
					(size 1.27 1.27)
				)
				(hide yes)
			)
		)
		(property "Value" "GND"
			(at 50.165 184.785 0)
			(effects
				(font
					(size 1.27 1.27)
					(thickness 0.15)
				)
				(justify left bottom)
			)
		)
		(property "Footprint" ""
			(at 60.96 187.96 0)
			(effects
				(font
					(size 1.27 1.27)
					(thickness 0.15)
				)
				(justify left bottom)
				(hide yes)
			)
		)
		(property "Datasheet" ""
			(at 60.96 193.04 0)
			(effects
				(font
					(size 1.27 1.27)
					(thickness 0.15)
				)
				(justify left bottom)
				(hide yes)
			)
		)
		(property "Description" ""
			(at 52.07 180.34 0)
			(effects
				(font
					(size 1.27 1.27)
				)
				(hide yes)
			)
		)
		(property "Author" "Antmicro"
			(at 60.96 185.42 0)
			(effects
				(font
					(size 1.27 1.27)
					(thickness 0.15)
				)
				(justify left bottom)
				(hide yes)
			)
		)
		(property "License" "Apache-2.0"
			(at 60.96 187.96 0)
			(effects
				(font
					(size 1.27 1.27)
					(thickness 0.15)
				)
				(justify left bottom)
				(hide yes)
			)
		)
		(pin "1"
		)
		(instances
			(project "data-center-rdimm-ddr5-tester"
				(path ""
					(reference "#PWR0343")
					(unit 1)
				)
			)
		)
	)
	(symbol
		(lib_id "antmicroMemory:AT24CS01_SOT23")
		(at 248.92 261.62 0)
		(unit 1)
		(exclude_from_sim no)
		(in_bom yes)
		(on_board yes)
		(dnp no)
		(fields_autoplaced yes)
		(property "Reference" "U29"
			(at 259.08 254 0)
			(effects
				(font
					(size 1.27 1.27)
					(thickness 0.15)
				)
			)
		)
		(property "Value" "AT24CS01_SOT23"
			(at 284.48 266.7 0)
			(effects
				(font
					(size 1.27 1.27)
					(thickness 0.15)
				)
				(justify left bottom)
				(hide yes)
			)
		)
		(property "Footprint" "antmicro-footprints:SOT-23-5"
			(at 284.48 269.24 0)
			(effects
				(font
					(size 1.27 1.27)
					(thickness 0.15)
				)
				(justify left bottom)
				(hide yes)
			)
		)
		(property "Datasheet" "http://ww1.microchip.com/downloads/en/devicedoc/Atmel-8815-SEEPROM-AT24CS01-02-Datasheet.pdf"
			(at 284.48 271.78 0)
			(effects
				(font
					(size 1.27 1.27)
					(thickness 0.15)
				)
				(justify left bottom)
				(hide yes)
			)
		)
		(property "Description" ""
			(at 248.92 261.62 0)
			(effects
				(font
					(size 1.27 1.27)
				)
				(hide yes)
			)
		)
		(property "Manufacturer" "Atmel"
			(at 284.48 274.32 0)
			(effects
				(font
					(size 1.27 1.27)
					(thickness 0.15)
				)
				(justify left bottom)
				(hide yes)
			)
		)
		(property "MPN" "AT24CS01-ST"
			(at 259.08 256.54 0)
			(effects
				(font
					(size 1.27 1.27)
					(thickness 0.15)
				)
			)
		)
		(property "Author" "Antmicro"
			(at 284.48 279.4 0)
			(effects
				(font
					(size 1.27 1.27)
					(thickness 0.15)
				)
				(justify left bottom)
				(hide yes)
			)
		)
		(property "License" "Apache-2.0"
			(at 284.48 281.94 0)
			(effects
				(font
					(size 1.27 1.27)
					(thickness 0.15)
				)
				(justify left bottom)
				(hide yes)
			)
		)
		(pin "2"
		)
		(pin "4"
		)
		(pin "1"
		)
		(pin "5"
		)
		(pin "3"
		)
		(instances
			(project "data-center-rdimm-ddr5-tester"
				(path ""
					(reference "U29")
					(unit 1)
				)
			)
		)
	)
	(symbol
		(lib_id "antmicroResistors0402:R_47k_0402")
		(at 325.12 86.36 90)
		(unit 1)
		(exclude_from_sim no)
		(in_bom yes)
		(on_board yes)
		(dnp no)
		(fields_autoplaced yes)
		(property "Reference" "R249"
			(at 327.66 82.55 90)
			(effects
				(font
					(size 1.27 1.27)
					(thickness 0.15)
				)
				(justify right)
			)
		)
		(property "Value" "R_47k_0402"
			(at 337.82 66.04 0)
			(effects
				(font
					(size 1.27 1.27)
					(thickness 0.15)
				)
				(justify left bottom)
				(hide yes)
			)
		)
		(property "Footprint" "antmicro-footprints:R_0402_1005Metric"
			(at 340.36 66.04 0)
			(effects
				(font
					(size 1.27 1.27)
					(thickness 0.15)
				)
				(justify left bottom)
				(hide yes)
			)
		)
		(property "Datasheet" "https://www.bourns.com/docs/product-datasheets/cr.pdf"
			(at 342.9 66.04 0)
			(effects
				(font
					(size 1.27 1.27)
					(thickness 0.15)
				)
				(justify left bottom)
				(hide yes)
			)
		)
		(property "Description" ""
			(at 325.12 86.36 0)
			(effects
				(font
					(size 1.27 1.27)
				)
				(hide yes)
			)
		)
		(property "MPN" "CR0402-FX-4702GLF"
			(at 345.44 66.04 0)
			(effects
				(font
					(size 1.27 1.27)
					(thickness 0.15)
				)
				(justify left bottom)
				(hide yes)
			)
		)
		(property "Manufacturer" "Bourns"
			(at 347.98 66.04 0)
			(effects
				(font
					(size 1.27 1.27)
					(thickness 0.15)
				)
				(justify left bottom)
				(hide yes)
			)
		)
		(property "License" "Apache-2.0"
			(at 350.52 66.04 0)
			(effects
				(font
					(size 1.27 1.27)
					(thickness 0.15)
				)
				(justify left bottom)
				(hide yes)
			)
		)
		(property "Author" "Antmicro"
			(at 353.06 66.04 0)
			(effects
				(font
					(size 1.27 1.27)
					(thickness 0.15)
				)
				(justify left bottom)
				(hide yes)
			)
		)
		(property "Val" "47k"
			(at 327.66 85.09 90)
			(effects
				(font
					(size 1.27 1.27)
					(thickness 0.15)
				)
				(justify right)
			)
		)
		(property "Tolerance" "1%"
			(at 335.28 66.04 0)
			(effects
				(font
					(size 1.27 1.27)
				)
				(justify left bottom)
				(hide yes)
			)
		)
		(pin "2"
		)
		(pin "1"
		)
		(instances
			(project "data-center-rdimm-ddr5-tester"
				(path ""
					(reference "R249")
					(unit 1)
				)
			)
		)
	)
	(symbol
		(lib_id "antmicroCapacitors0402:C_100n_0402")
		(at 284.48 261.62 270)
		(unit 1)
		(exclude_from_sim no)
		(in_bom yes)
		(on_board yes)
		(dnp no)
		(fields_autoplaced yes)
		(property "Reference" "C207"
			(at 281.94 262.8963 90)
			(effects
				(font
					(size 1.27 1.27)
				)
				(justify right)
			)
		)
		(property "Value" "C_100n_0402"
			(at 274.32 281.94 0)
			(effects
				(font
					(size 1.27 1.27)
					(thickness 0.15)
				)
				(justify left bottom)
				(hide yes)
			)
		)
		(property "Footprint" "antmicro-footprints:C_0402_1005Metric"
			(at 271.78 281.94 0)
			(effects
				(font
					(size 1.27 1.27)
					(thickness 0.15)
				)
				(justify left bottom)
				(hide yes)
			)
		)
		(property "Datasheet" "https://www.murata.com/products/productdetail?partno=GRM155R61H104KE14%23"
			(at 269.24 281.94 0)
			(effects
				(font
					(size 1.27 1.27)
					(thickness 0.15)
				)
				(justify left bottom)
				(hide yes)
			)
		)
		(property "Description" ""
			(at 284.48 261.62 0)
			(effects
				(font
					(size 1.27 1.27)
				)
				(hide yes)
			)
		)
		(property "Manufacturer" "Murata"
			(at 264.16 281.94 0)
			(effects
				(font
					(size 1.27 1.27)
					(thickness 0.15)
				)
				(justify left bottom)
				(hide yes)
			)
		)
		(property "MPN" "GRM155R61H104KE14D"
			(at 266.7 281.94 0)
			(effects
				(font
					(size 1.27 1.27)
					(thickness 0.15)
				)
				(justify left bottom)
				(hide yes)
			)
		)
		(property "Val" "100n"
			(at 281.94 266.0712 90)
			(effects
				(font
					(size 1.27 1.27)
					(thickness 0.15)
				)
				(justify right)
			)
		)
		(property "License" "Apache-2.0"
			(at 261.62 281.94 0)
			(effects
				(font
					(size 1.27 1.27)
					(thickness 0.15)
				)
				(justify left bottom)
				(hide yes)
			)
		)
		(property "Author" "Antmicro"
			(at 259.08 281.94 0)
			(effects
				(font
					(size 1.27 1.27)
					(thickness 0.15)
				)
				(justify left bottom)
				(hide yes)
			)
		)
		(property "Voltage" "50V"
			(at 256.54 281.94 0)
			(effects
				(font
					(size 1.27 1.27)
				)
				(justify left bottom)
				(hide yes)
			)
		)
		(property "Dielectric" "X5R"
			(at 254 281.94 0)
			(effects
				(font
					(size 1.27 1.27)
				)
				(justify left bottom)
				(hide yes)
			)
		)
		(pin "1"
		)
		(pin "2"
		)
		(instances
			(project "data-center-rdimm-ddr5-tester"
				(path ""
					(reference "C207")
					(unit 1)
				)
			)
		)
	)
	(symbol
		(lib_id "antmicropower:+3V3_AON")
		(at 273.05 260.35 0)
		(unit 1)
		(exclude_from_sim no)
		(in_bom yes)
		(on_board yes)
		(dnp no)
		(property "Reference" "#PWR0392"
			(at 273.05 264.16 0)
			(effects
				(font
					(size 1.27 1.27)
				)
				(hide yes)
			)
		)
		(property "Value" "+3V3_AON"
			(at 273.05 256.54 0)
			(effects
				(font
					(size 1.27 1.27)
				)
			)
		)
		(property "Footprint" ""
			(at 273.05 260.35 0)
			(effects
				(font
					(size 1.27 1.27)
				)
				(hide yes)
			)
		)
		(property "Datasheet" ""
			(at 273.05 260.35 0)
			(effects
				(font
					(size 1.27 1.27)
				)
				(hide yes)
			)
		)
		(property "Description" ""
			(at 273.05 260.35 0)
			(effects
				(font
					(size 1.27 1.27)
				)
				(hide yes)
			)
		)
		(pin "1"
		)
		(instances
			(project "data-center-rdimm-ddr5-tester"
				(path ""
					(reference "#PWR0392")
					(unit 1)
				)
			)
		)
	)
	(symbol
		(lib_id "antmicroResistors0402:R_47k_0402")
		(at 63.5 220.98 90)
		(unit 1)
		(exclude_from_sim no)
		(in_bom yes)
		(on_board yes)
		(dnp no)
		(fields_autoplaced yes)
		(property "Reference" "R140"
			(at 65.151 217.6094 90)
			(effects
				(font
					(size 1.27 1.27)
				)
				(justify right)
			)
		)
		(property "Value" "R_47k_0402"
			(at 76.2 200.66 0)
			(effects
				(font
					(size 1.27 1.27)
					(thickness 0.15)
				)
				(justify left bottom)
				(hide yes)
			)
		)
		(property "Footprint" "antmicro-footprints:R_0402_1005Metric"
			(at 78.74 200.66 0)
			(effects
				(font
					(size 1.27 1.27)
					(thickness 0.15)
				)
				(justify left bottom)
				(hide yes)
			)
		)
		(property "Datasheet" "https://www.bourns.com/docs/product-datasheets/cr.pdf"
			(at 81.28 200.66 0)
			(effects
				(font
					(size 1.27 1.27)
					(thickness 0.15)
				)
				(justify left bottom)
				(hide yes)
			)
		)
		(property "Description" ""
			(at 63.5 220.98 0)
			(effects
				(font
					(size 1.27 1.27)
				)
				(hide yes)
			)
		)
		(property "Manufacturer" "Bourns"
			(at 86.36 200.66 0)
			(effects
				(font
					(size 1.27 1.27)
					(thickness 0.15)
				)
				(justify left bottom)
				(hide yes)
			)
		)
		(property "MPN" "CR0402-FX-4702GLF"
			(at 83.82 200.66 0)
			(effects
				(font
					(size 1.27 1.27)
					(thickness 0.15)
				)
				(justify left bottom)
				(hide yes)
			)
		)
		(property "Val" "47k"
			(at 65.151 220.1397 90)
			(effects
				(font
					(size 1.27 1.27)
					(thickness 0.15)
				)
				(justify right)
			)
		)
		(property "License" "Apache-2.0"
			(at 88.9 200.66 0)
			(effects
				(font
					(size 1.27 1.27)
					(thickness 0.15)
				)
				(justify left bottom)
				(hide yes)
			)
		)
		(property "Author" "Antmicro"
			(at 91.44 200.66 0)
			(effects
				(font
					(size 1.27 1.27)
					(thickness 0.15)
				)
				(justify left bottom)
				(hide yes)
			)
		)
		(property "Tolerance" "1%"
			(at 73.66 200.66 0)
			(effects
				(font
					(size 1.27 1.27)
				)
				(justify left bottom)
				(hide yes)
			)
		)
		(pin "1"
		)
		(pin "2"
		)
		(instances
			(project "data-center-rdimm-ddr5-tester"
				(path ""
					(reference "R140")
					(unit 1)
				)
			)
		)
	)
	(symbol
		(lib_id "antmicropower:GND")
		(at 273.05 266.7 0)
		(unit 1)
		(exclude_from_sim no)
		(in_bom yes)
		(on_board yes)
		(dnp no)
		(fields_autoplaced yes)
		(property "Reference" "#PWR0395"
			(at 273.05 273.05 0)
			(effects
				(font
					(size 1.27 1.27)
				)
				(hide yes)
			)
		)
		(property "Value" "GND"
			(at 271.145 271.145 0)
			(effects
				(font
					(size 1.27 1.27)
					(thickness 0.15)
				)
				(justify left bottom)
			)
		)
		(property "Footprint" ""
			(at 281.94 274.32 0)
			(effects
				(font
					(size 1.27 1.27)
					(thickness 0.15)
				)
				(justify left bottom)
				(hide yes)
			)
		)
		(property "Datasheet" ""
			(at 281.94 279.4 0)
			(effects
				(font
					(size 1.27 1.27)
					(thickness 0.15)
				)
				(justify left bottom)
				(hide yes)
			)
		)
		(property "Description" ""
			(at 273.05 266.7 0)
			(effects
				(font
					(size 1.27 1.27)
				)
				(hide yes)
			)
		)
		(property "Author" "Antmicro"
			(at 281.94 271.78 0)
			(effects
				(font
					(size 1.27 1.27)
					(thickness 0.15)
				)
				(justify left bottom)
				(hide yes)
			)
		)
		(property "License" "Apache-2.0"
			(at 281.94 274.32 0)
			(effects
				(font
					(size 1.27 1.27)
					(thickness 0.15)
				)
				(justify left bottom)
				(hide yes)
			)
		)
		(pin "1"
		)
		(instances
			(project "data-center-rdimm-ddr5-tester"
				(path ""
					(reference "#PWR0395")
					(unit 1)
				)
			)
		)
	)
	(symbol
		(lib_id "antmicropower:GND")
		(at 111.76 161.29 0)
		(unit 1)
		(exclude_from_sim no)
		(in_bom yes)
		(on_board yes)
		(dnp no)
		(fields_autoplaced yes)
		(property "Reference" "#PWR0333"
			(at 111.76 167.64 0)
			(effects
				(font
					(size 1.27 1.27)
				)
				(hide yes)
			)
		)
		(property "Value" "GND"
			(at 109.855 165.735 0)
			(effects
				(font
					(size 1.27 1.27)
					(thickness 0.15)
				)
				(justify left bottom)
			)
		)
		(property "Footprint" ""
			(at 120.65 168.91 0)
			(effects
				(font
					(size 1.27 1.27)
					(thickness 0.15)
				)
				(justify left bottom)
				(hide yes)
			)
		)
		(property "Datasheet" ""
			(at 120.65 173.99 0)
			(effects
				(font
					(size 1.27 1.27)
					(thickness 0.15)
				)
				(justify left bottom)
				(hide yes)
			)
		)
		(property "Description" ""
			(at 111.76 161.29 0)
			(effects
				(font
					(size 1.27 1.27)
				)
				(hide yes)
			)
		)
		(property "Author" "Antmicro"
			(at 120.65 166.37 0)
			(effects
				(font
					(size 1.27 1.27)
					(thickness 0.15)
				)
				(justify left bottom)
				(hide yes)
			)
		)
		(property "License" "Apache-2.0"
			(at 120.65 168.91 0)
			(effects
				(font
					(size 1.27 1.27)
					(thickness 0.15)
				)
				(justify left bottom)
				(hide yes)
			)
		)
		(pin "1"
		)
		(instances
			(project "data-center-rdimm-ddr5-tester"
				(path ""
					(reference "#PWR0333")
					(unit 1)
				)
			)
		)
	)
	(symbol
		(lib_id "antmicropower:GND")
		(at 316.23 87.63 0)
		(unit 1)
		(exclude_from_sim no)
		(in_bom yes)
		(on_board yes)
		(dnp no)
		(fields_autoplaced yes)
		(property "Reference" "#PWR0546"
			(at 316.23 93.98 0)
			(effects
				(font
					(size 1.27 1.27)
				)
				(hide yes)
			)
		)
		(property "Value" "GND"
			(at 314.325 92.075 0)
			(effects
				(font
					(size 1.27 1.27)
					(thickness 0.15)
				)
				(justify left bottom)
			)
		)
		(property "Footprint" ""
			(at 325.12 95.25 0)
			(effects
				(font
					(size 1.27 1.27)
					(thickness 0.15)
				)
				(justify left bottom)
				(hide yes)
			)
		)
		(property "Datasheet" ""
			(at 325.12 100.33 0)
			(effects
				(font
					(size 1.27 1.27)
					(thickness 0.15)
				)
				(justify left bottom)
				(hide yes)
			)
		)
		(property "Description" ""
			(at 316.23 87.63 0)
			(effects
				(font
					(size 1.27 1.27)
				)
				(hide yes)
			)
		)
		(property "Author" "Antmicro"
			(at 325.12 92.71 0)
			(effects
				(font
					(size 1.27 1.27)
					(thickness 0.15)
				)
				(justify left bottom)
				(hide yes)
			)
		)
		(property "License" "Apache-2.0"
			(at 325.12 95.25 0)
			(effects
				(font
					(size 1.27 1.27)
					(thickness 0.15)
				)
				(justify left bottom)
				(hide yes)
			)
		)
		(pin "1"
		)
		(instances
			(project "data-center-rdimm-ddr5-tester"
				(path ""
					(reference "#PWR0546")
					(unit 1)
				)
			)
		)
	)
	(symbol
		(lib_id "antmicroTransistorsFETsMOSFETsSingle:BSS138PW")
		(at 172.72 187.96 0)
		(unit 1)
		(exclude_from_sim no)
		(in_bom yes)
		(on_board yes)
		(dnp no)
		(fields_autoplaced yes)
		(property "Reference" "Q16"
			(at 184.15 184.15 0)
			(effects
				(font
					(size 1.27 1.27)
					(thickness 0.15)
				)
				(justify left)
			)
		)
		(property "Value" "BSS138PW"
			(at 195.58 196.85 0)
			(effects
				(font
					(size 1.27 1.27)
					(thickness 0.15)
				)
				(justify left bottom)
				(hide yes)
			)
		)
		(property "Footprint" "antmicro-footprints:SC70-3"
			(at 195.58 199.39 0)
			(effects
				(font
					(size 1.27 1.27)
					(thickness 0.15)
				)
				(justify left bottom)
				(hide yes)
			)
		)
		(property "Datasheet" "https://assets.nexperia.com/documents/data-sheet/BSS138PW.pdf"
			(at 195.58 201.93 0)
			(effects
				(font
					(size 1.27 1.27)
					(thickness 0.15)
				)
				(justify left bottom)
				(hide yes)
			)
		)
		(property "Description" ""
			(at 172.72 187.96 0)
			(effects
				(font
					(size 1.27 1.27)
				)
				(hide yes)
			)
		)
		(property "MPN" "BSS138PW"
			(at 184.15 186.69 0)
			(effects
				(font
					(size 1.27 1.27)
					(thickness 0.15)
				)
				(justify left)
			)
		)
		(property "Manufacturer" "Nexperia"
			(at 195.58 207.01 0)
			(effects
				(font
					(size 1.27 1.27)
					(thickness 0.15)
				)
				(justify left bottom)
				(hide yes)
			)
		)
		(property "Author" "Antmicro"
			(at 195.58 209.55 0)
			(effects
				(font
					(size 1.27 1.27)
					(thickness 0.15)
				)
				(justify left bottom)
				(hide yes)
			)
		)
		(property "License" "Apache-2.0"
			(at 195.58 212.09 0)
			(effects
				(font
					(size 1.27 1.27)
					(thickness 0.15)
				)
				(justify left bottom)
				(hide yes)
			)
		)
		(pin "1"
		)
		(pin "3"
		)
		(pin "2"
		)
		(instances
			(project "data-center-rdimm-ddr5-tester"
				(path ""
					(reference "Q16")
					(unit 1)
				)
			)
		)
	)
	(symbol
		(lib_id "antmicroPMICPowerSequencers:MAX812REUS+T")
		(at 205.74 186.69 0)
		(unit 1)
		(exclude_from_sim no)
		(in_bom yes)
		(on_board yes)
		(dnp no)
		(fields_autoplaced yes)
		(property "Reference" "U26"
			(at 213.36 179.07 0)
			(effects
				(font
					(size 1.27 1.27)
					(thickness 0.15)
				)
			)
		)
		(property "Value" "MAX812REUS+T"
			(at 236.22 191.77 0)
			(effects
				(font
					(size 1.27 1.27)
					(thickness 0.15)
				)
				(justify left bottom)
				(hide yes)
			)
		)
		(property "Footprint" "antmicro-footprints:SOT-143-4"
			(at 236.22 194.31 0)
			(effects
				(font
					(size 1.27 1.27)
					(thickness 0.15)
				)
				(justify left bottom)
				(hide yes)
			)
		)
		(property "Datasheet" "https://datasheets.maximintegrated.com/en/ds/MAX811-MAX812T.pdf"
			(at 236.22 196.85 0)
			(effects
				(font
					(size 1.27 1.27)
					(thickness 0.15)
				)
				(justify left bottom)
				(hide yes)
			)
		)
		(property "Description" ""
			(at 205.74 186.69 0)
			(effects
				(font
					(size 1.27 1.27)
				)
				(hide yes)
			)
		)
		(property "Manufacturer" "Maxim Integrated Products"
			(at 236.22 199.39 0)
			(effects
				(font
					(size 1.27 1.27)
					(thickness 0.15)
				)
				(justify left bottom)
				(hide yes)
			)
		)
		(property "MPN" "MAX812REUS+T"
			(at 213.36 181.61 0)
			(effects
				(font
					(size 1.27 1.27)
					(thickness 0.15)
				)
			)
		)
		(property "License" "Apache-2.0"
			(at 236.22 204.47 0)
			(effects
				(font
					(size 1.27 1.27)
					(thickness 0.15)
				)
				(justify left bottom)
				(hide yes)
			)
		)
		(property "Author" "Antmicro"
			(at 236.22 207.01 0)
			(effects
				(font
					(size 1.27 1.27)
					(thickness 0.15)
				)
				(justify left bottom)
				(hide yes)
			)
		)
		(pin "1"
		)
		(pin "4"
		)
		(pin "2"
		)
		(pin "3"
		)
		(instances
			(project "data-center-rdimm-ddr5-tester"
				(path ""
					(reference "U26")
					(unit 1)
				)
			)
		)
	)
	(symbol
		(lib_id "antmicroCapacitors0402:C_100n_0402")
		(at 77.47 62.23 90)
		(unit 1)
		(exclude_from_sim no)
		(in_bom yes)
		(on_board yes)
		(dnp no)
		(property "Reference" "C175"
			(at 80.01 58.4135 90)
			(effects
				(font
					(size 1.27 1.27)
				)
				(justify right)
			)
		)
		(property "Value" "C_100n_0402"
			(at 87.63 41.91 0)
			(effects
				(font
					(size 1.27 1.27)
					(thickness 0.15)
				)
				(justify left bottom)
				(hide yes)
			)
		)
		(property "Footprint" "antmicro-footprints:C_0402_1005Metric"
			(at 90.17 41.91 0)
			(effects
				(font
					(size 1.27 1.27)
					(thickness 0.15)
				)
				(justify left bottom)
				(hide yes)
			)
		)
		(property "Datasheet" "https://www.murata.com/products/productdetail?partno=GRM155R61H104KE14%23"
			(at 92.71 41.91 0)
			(effects
				(font
					(size 1.27 1.27)
					(thickness 0.15)
				)
				(justify left bottom)
				(hide yes)
			)
		)
		(property "Description" ""
			(at 77.47 62.23 0)
			(effects
				(font
					(size 1.27 1.27)
				)
				(hide yes)
			)
		)
		(property "Manufacturer" "Murata"
			(at 97.79 41.91 0)
			(effects
				(font
					(size 1.27 1.27)
					(thickness 0.15)
				)
				(justify left bottom)
				(hide yes)
			)
		)
		(property "MPN" "GRM155R61H104KE14D"
			(at 95.25 41.91 0)
			(effects
				(font
					(size 1.27 1.27)
					(thickness 0.15)
				)
				(justify left bottom)
				(hide yes)
			)
		)
		(property "Val" "100n"
			(at 80.01 60.9535 90)
			(effects
				(font
					(size 1.27 1.27)
					(thickness 0.15)
				)
				(justify right)
			)
		)
		(property "License" "Apache-2.0"
			(at 100.33 41.91 0)
			(effects
				(font
					(size 1.27 1.27)
					(thickness 0.15)
				)
				(justify left bottom)
				(hide yes)
			)
		)
		(property "Author" "Antmicro"
			(at 102.87 41.91 0)
			(effects
				(font
					(size 1.27 1.27)
					(thickness 0.15)
				)
				(justify left bottom)
				(hide yes)
			)
		)
		(property "Voltage" "50V"
			(at 105.41 41.91 0)
			(effects
				(font
					(size 1.27 1.27)
				)
				(justify left bottom)
				(hide yes)
			)
		)
		(property "Dielectric" "X5R"
			(at 107.95 41.91 0)
			(effects
				(font
					(size 1.27 1.27)
				)
				(justify left bottom)
				(hide yes)
			)
		)
		(pin "1"
		)
		(pin "2"
		)
		(instances
			(project "data-center-rdimm-ddr5-tester"
				(path ""
					(reference "C175")
					(unit 1)
				)
			)
		)
	)
	(symbol
		(lib_id "antmicroCapacitors0402:C_100n_0402")
		(at 179.07 95.25 270)
		(mirror x)
		(unit 1)
		(exclude_from_sim no)
		(in_bom yes)
		(on_board yes)
		(dnp no)
		(property "Reference" "C328"
			(at 177.8 90.805 90)
			(effects
				(font
					(size 1.27 1.27)
				)
				(justify right)
			)
		)
		(property "Value" "C_100n_0402"
			(at 168.91 74.93 0)
			(effects
				(font
					(size 1.27 1.27)
					(thickness 0.15)
				)
				(justify left bottom)
				(hide yes)
			)
		)
		(property "Footprint" "antmicro-footprints:C_0402_1005Metric"
			(at 166.37 74.93 0)
			(effects
				(font
					(size 1.27 1.27)
					(thickness 0.15)
				)
				(justify left bottom)
				(hide yes)
			)
		)
		(property "Datasheet" "https://www.murata.com/products/productdetail?partno=GRM155R61H104KE14%23"
			(at 163.83 74.93 0)
			(effects
				(font
					(size 1.27 1.27)
					(thickness 0.15)
				)
				(justify left bottom)
				(hide yes)
			)
		)
		(property "Description" ""
			(at 179.07 95.25 0)
			(effects
				(font
					(size 1.27 1.27)
				)
			)
		)
		(property "Manufacturer" "Murata"
			(at 158.75 74.93 0)
			(effects
				(font
					(size 1.27 1.27)
					(thickness 0.15)
				)
				(justify left bottom)
				(hide yes)
			)
		)
		(property "MPN" "GRM155R61H104KE14D"
			(at 161.29 74.93 0)
			(effects
				(font
					(size 1.27 1.27)
					(thickness 0.15)
				)
				(justify left bottom)
				(hide yes)
			)
		)
		(property "Val" "100n"
			(at 177.8 94.615 90)
			(effects
				(font
					(size 1.27 1.27)
					(thickness 0.15)
				)
				(justify right)
			)
		)
		(property "License" "Apache-2.0"
			(at 156.21 74.93 0)
			(effects
				(font
					(size 1.27 1.27)
					(thickness 0.15)
				)
				(justify left bottom)
				(hide yes)
			)
		)
		(property "Author" "Antmicro"
			(at 153.67 74.93 0)
			(effects
				(font
					(size 1.27 1.27)
					(thickness 0.15)
				)
				(justify left bottom)
				(hide yes)
			)
		)
		(property "Voltage" "50V"
			(at 151.13 74.93 0)
			(effects
				(font
					(size 1.27 1.27)
				)
				(justify left bottom)
				(hide yes)
			)
		)
		(property "Dielectric" "X5R"
			(at 148.59 74.93 0)
			(effects
				(font
					(size 1.27 1.27)
				)
				(justify left bottom)
				(hide yes)
			)
		)
		(pin "1"
		)
		(pin "2"
		)
		(instances
			(project "data-center-rdimm-ddr5-tester"
				(path ""
					(reference "C328")
					(unit 1)
				)
			)
		)
	)
	(symbol
		(lib_id "antmicropower:GND")
		(at 233.68 105.41 0)
		(mirror y)
		(unit 1)
		(exclude_from_sim no)
		(in_bom yes)
		(on_board yes)
		(dnp no)
		(property "Reference" "#PWR0553"
			(at 233.68 111.76 0)
			(effects
				(font
					(size 1.27 1.27)
				)
				(hide yes)
			)
		)
		(property "Value" "GND"
			(at 231.521 109.347 0)
			(effects
				(font
					(size 1.27 1.27)
					(thickness 0.15)
				)
				(justify right)
			)
		)
		(property "Footprint" ""
			(at 224.79 113.03 0)
			(effects
				(font
					(size 1.27 1.27)
					(thickness 0.15)
				)
				(justify left bottom)
				(hide yes)
			)
		)
		(property "Datasheet" ""
			(at 224.79 118.11 0)
			(effects
				(font
					(size 1.27 1.27)
					(thickness 0.15)
				)
				(justify left bottom)
				(hide yes)
			)
		)
		(property "Description" ""
			(at 224.79 120.65 0)
			(effects
				(font
					(size 1.27 1.27)
				)
				(justify left bottom)
				(hide yes)
			)
		)
		(property "Author" "Antmicro"
			(at 224.79 113.03 0)
			(effects
				(font
					(size 1.27 1.27)
					(thickness 0.15)
				)
				(justify left bottom)
				(hide yes)
			)
		)
		(property "License" "Apache-2.0"
			(at 224.79 115.57 0)
			(effects
				(font
					(size 1.27 1.27)
					(thickness 0.15)
				)
				(justify left bottom)
				(hide yes)
			)
		)
		(pin "1"
		)
		(instances
			(project "data-center-rdimm-ddr5-tester"
				(path ""
					(reference "#PWR0553")
					(unit 1)
				)
			)
		)
	)
	(symbol
		(lib_id "antmicroResistors0402:R_47k_0402")
		(at 39.37 177.8 90)
		(unit 1)
		(exclude_from_sim no)
		(in_bom yes)
		(on_board yes)
		(dnp no)
		(property "Reference" "R161"
			(at 38.1 173.99 90)
			(effects
				(font
					(size 1.27 1.27)
				)
				(justify left)
			)
		)
		(property "Value" "R_47k_0402"
			(at 52.07 157.48 0)
			(effects
				(font
					(size 1.27 1.27)
					(thickness 0.15)
				)
				(justify left bottom)
				(hide yes)
			)
		)
		(property "Footprint" "antmicro-footprints:R_0402_1005Metric"
			(at 54.61 157.48 0)
			(effects
				(font
					(size 1.27 1.27)
					(thickness 0.15)
				)
				(justify left bottom)
				(hide yes)
			)
		)
		(property "Datasheet" "https://www.bourns.com/docs/product-datasheets/cr.pdf"
			(at 57.15 157.48 0)
			(effects
				(font
					(size 1.27 1.27)
					(thickness 0.15)
				)
				(justify left bottom)
				(hide yes)
			)
		)
		(property "Description" ""
			(at 39.37 177.8 0)
			(effects
				(font
					(size 1.27 1.27)
				)
				(hide yes)
			)
		)
		(property "Manufacturer" "Bourns"
			(at 62.23 157.48 0)
			(effects
				(font
					(size 1.27 1.27)
					(thickness 0.15)
				)
				(justify left bottom)
				(hide yes)
			)
		)
		(property "MPN" "CR0402-FX-4702GLF"
			(at 59.69 157.48 0)
			(effects
				(font
					(size 1.27 1.27)
					(thickness 0.15)
				)
				(justify left bottom)
				(hide yes)
			)
		)
		(property "Val" "47k"
			(at 38.1 176.53 90)
			(effects
				(font
					(size 1.27 1.27)
					(thickness 0.15)
				)
				(justify left)
			)
		)
		(property "License" "Apache-2.0"
			(at 64.77 157.48 0)
			(effects
				(font
					(size 1.27 1.27)
					(thickness 0.15)
				)
				(justify left bottom)
				(hide yes)
			)
		)
		(property "Author" "Antmicro"
			(at 67.31 157.48 0)
			(effects
				(font
					(size 1.27 1.27)
					(thickness 0.15)
				)
				(justify left bottom)
				(hide yes)
			)
		)
		(property "Tolerance" "1%"
			(at 49.53 157.48 0)
			(effects
				(font
					(size 1.27 1.27)
				)
				(justify left bottom)
				(hide yes)
			)
		)
		(pin "1"
		)
		(pin "2"
		)
		(instances
			(project "data-center-rdimm-ddr5-tester"
				(path ""
					(reference "R161")
					(unit 1)
				)
			)
		)
	)
	(symbol
		(lib_id "antmicroResistors0402:R_0R_0402")
		(at 176.53 264.16 0)
		(unit 1)
		(exclude_from_sim no)
		(in_bom yes)
		(on_board yes)
		(dnp no)
		(property "Reference" "R136"
			(at 184.15 262.89 0)
			(effects
				(font
					(size 1.27 1.27)
					(thickness 0.15)
				)
			)
		)
		(property "Value" "R_0R_0402"
			(at 196.85 276.86 0)
			(effects
				(font
					(size 1.27 1.27)
					(thickness 0.15)
				)
				(justify left bottom)
				(hide yes)
			)
		)
		(property "Footprint" "antmicro-footprints:R_0402_1005Metric"
			(at 196.85 279.4 0)
			(effects
				(font
					(size 1.27 1.27)
					(thickness 0.15)
				)
				(justify left bottom)
				(hide yes)
			)
		)
		(property "Datasheet" "https://industrial.panasonic.com/cdbs/www-data/pdf/RDA0000/AOA0000C301.pdf"
			(at 196.85 281.94 0)
			(effects
				(font
					(size 1.27 1.27)
					(thickness 0.15)
				)
				(justify left bottom)
				(hide yes)
			)
		)
		(property "Description" ""
			(at 176.53 264.16 0)
			(effects
				(font
					(size 1.27 1.27)
				)
				(hide yes)
			)
		)
		(property "MPN" "ERJ2GE0R00X"
			(at 196.85 284.48 0)
			(effects
				(font
					(size 1.27 1.27)
					(thickness 0.15)
				)
				(justify left bottom)
				(hide yes)
			)
		)
		(property "Manufacturer" "Panasonic"
			(at 196.85 287.02 0)
			(effects
				(font
					(size 1.27 1.27)
					(thickness 0.15)
				)
				(justify left bottom)
				(hide yes)
			)
		)
		(property "License" "Apache-2.0"
			(at 196.85 289.56 0)
			(effects
				(font
					(size 1.27 1.27)
					(thickness 0.15)
				)
				(justify left bottom)
				(hide yes)
			)
		)
		(property "Author" "Antmicro"
			(at 196.85 292.1 0)
			(effects
				(font
					(size 1.27 1.27)
					(thickness 0.15)
				)
				(justify left bottom)
				(hide yes)
			)
		)
		(property "Val" "0R"
			(at 175.26 262.89 0)
			(effects
				(font
					(size 1.27 1.27)
					(thickness 0.15)
				)
			)
		)
		(property "Tolerance" "~"
			(at 196.85 274.32 0)
			(effects
				(font
					(size 1.27 1.27)
				)
				(justify left bottom)
				(hide yes)
			)
		)
		(property "Current" "1A"
			(at 196.85 294.64 0)
			(effects
				(font
					(size 1.27 1.27)
					(thickness 0.15)
				)
				(justify left bottom)
				(hide yes)
			)
		)
		(pin "1"
		)
		(pin "2"
		)
		(instances
			(project "data-center-rdimm-ddr5-tester"
				(path ""
					(reference "R136")
					(unit 1)
				)
			)
		)
	)
	(symbol
		(lib_id "antmicropower:GND")
		(at 86.36 66.04 0)
		(unit 1)
		(exclude_from_sim no)
		(in_bom yes)
		(on_board yes)
		(dnp no)
		(fields_autoplaced yes)
		(property "Reference" "#PWR0292"
			(at 86.36 72.39 0)
			(effects
				(font
					(size 1.27 1.27)
				)
				(hide yes)
			)
		)
		(property "Value" "GND"
			(at 84.455 70.485 0)
			(effects
				(font
					(size 1.27 1.27)
					(thickness 0.15)
				)
				(justify left bottom)
			)
		)
		(property "Footprint" ""
			(at 95.25 73.66 0)
			(effects
				(font
					(size 1.27 1.27)
					(thickness 0.15)
				)
				(justify left bottom)
				(hide yes)
			)
		)
		(property "Datasheet" ""
			(at 95.25 78.74 0)
			(effects
				(font
					(size 1.27 1.27)
					(thickness 0.15)
				)
				(justify left bottom)
				(hide yes)
			)
		)
		(property "Description" ""
			(at 86.36 66.04 0)
			(effects
				(font
					(size 1.27 1.27)
				)
				(hide yes)
			)
		)
		(property "Author" "Antmicro"
			(at 95.25 71.12 0)
			(effects
				(font
					(size 1.27 1.27)
					(thickness 0.15)
				)
				(justify left bottom)
				(hide yes)
			)
		)
		(property "License" "Apache-2.0"
			(at 95.25 73.66 0)
			(effects
				(font
					(size 1.27 1.27)
					(thickness 0.15)
				)
				(justify left bottom)
				(hide yes)
			)
		)
		(pin "1"
		)
		(instances
			(project "data-center-rdimm-ddr5-tester"
				(path ""
					(reference "#PWR0292")
					(unit 1)
				)
			)
		)
	)
	(symbol
		(lib_id "antmicropower:GND")
		(at 77.47 251.46 0)
		(unit 1)
		(exclude_from_sim no)
		(in_bom yes)
		(on_board yes)
		(dnp no)
		(property "Reference" "#PWR0525"
			(at 77.47 257.81 0)
			(effects
				(font
					(size 1.27 1.27)
				)
				(hide yes)
			)
		)
		(property "Value" "GND"
			(at 75.565 255.905 0)
			(effects
				(font
					(size 1.27 1.27)
					(thickness 0.15)
				)
				(justify left bottom)
			)
		)
		(property "Footprint" ""
			(at 86.36 259.08 0)
			(effects
				(font
					(size 1.27 1.27)
					(thickness 0.15)
				)
				(justify left bottom)
				(hide yes)
			)
		)
		(property "Datasheet" ""
			(at 86.36 264.16 0)
			(effects
				(font
					(size 1.27 1.27)
					(thickness 0.15)
				)
				(justify left bottom)
				(hide yes)
			)
		)
		(property "Description" ""
			(at 77.47 251.46 0)
			(effects
				(font
					(size 1.27 1.27)
				)
				(hide yes)
			)
		)
		(property "Author" "Antmicro"
			(at 86.36 256.54 0)
			(effects
				(font
					(size 1.27 1.27)
					(thickness 0.15)
				)
				(justify left bottom)
				(hide yes)
			)
		)
		(property "License" "Apache-2.0"
			(at 86.36 259.08 0)
			(effects
				(font
					(size 1.27 1.27)
					(thickness 0.15)
				)
				(justify left bottom)
				(hide yes)
			)
		)
		(pin "1"
		)
		(instances
			(project "data-center-rdimm-ddr5-tester"
				(path ""
					(reference "#PWR0525")
					(unit 1)
				)
			)
		)
	)
	(symbol
		(lib_id "antmicroResistors0402:R_0R_0402")
		(at 176.53 269.24 0)
		(unit 1)
		(exclude_from_sim no)
		(in_bom yes)
		(on_board yes)
		(dnp no)
		(property "Reference" "R138"
			(at 184.15 267.97 0)
			(effects
				(font
					(size 1.27 1.27)
					(thickness 0.15)
				)
			)
		)
		(property "Value" "R_0R_0402"
			(at 196.85 281.94 0)
			(effects
				(font
					(size 1.27 1.27)
					(thickness 0.15)
				)
				(justify left bottom)
				(hide yes)
			)
		)
		(property "Footprint" "antmicro-footprints:R_0402_1005Metric"
			(at 196.85 284.48 0)
			(effects
				(font
					(size 1.27 1.27)
					(thickness 0.15)
				)
				(justify left bottom)
				(hide yes)
			)
		)
		(property "Datasheet" "https://industrial.panasonic.com/cdbs/www-data/pdf/RDA0000/AOA0000C301.pdf"
			(at 196.85 287.02 0)
			(effects
				(font
					(size 1.27 1.27)
					(thickness 0.15)
				)
				(justify left bottom)
				(hide yes)
			)
		)
		(property "Description" ""
			(at 176.53 269.24 0)
			(effects
				(font
					(size 1.27 1.27)
				)
				(hide yes)
			)
		)
		(property "MPN" "ERJ2GE0R00X"
			(at 196.85 289.56 0)
			(effects
				(font
					(size 1.27 1.27)
					(thickness 0.15)
				)
				(justify left bottom)
				(hide yes)
			)
		)
		(property "Manufacturer" "Panasonic"
			(at 196.85 292.1 0)
			(effects
				(font
					(size 1.27 1.27)
					(thickness 0.15)
				)
				(justify left bottom)
				(hide yes)
			)
		)
		(property "License" "Apache-2.0"
			(at 196.85 294.64 0)
			(effects
				(font
					(size 1.27 1.27)
					(thickness 0.15)
				)
				(justify left bottom)
				(hide yes)
			)
		)
		(property "Author" "Antmicro"
			(at 196.85 297.18 0)
			(effects
				(font
					(size 1.27 1.27)
					(thickness 0.15)
				)
				(justify left bottom)
				(hide yes)
			)
		)
		(property "Val" "0R"
			(at 175.26 267.97 0)
			(effects
				(font
					(size 1.27 1.27)
					(thickness 0.15)
				)
			)
		)
		(property "Tolerance" "~"
			(at 196.85 279.4 0)
			(effects
				(font
					(size 1.27 1.27)
				)
				(justify left bottom)
				(hide yes)
			)
		)
		(property "Current" "1A"
			(at 196.85 299.72 0)
			(effects
				(font
					(size 1.27 1.27)
					(thickness 0.15)
				)
				(justify left bottom)
				(hide yes)
			)
		)
		(pin "1"
		)
		(pin "2"
		)
		(instances
			(project "data-center-rdimm-ddr5-tester"
				(path ""
					(reference "R138")
					(unit 1)
				)
			)
		)
	)
	(symbol
		(lib_id "antmicroCapacitors0402:C_1u_0402")
		(at 328.93 31.75 90)
		(unit 1)
		(exclude_from_sim no)
		(in_bom yes)
		(on_board yes)
		(dnp no)
		(property "Reference" "C198"
			(at 329.565 27.305 90)
			(effects
				(font
					(size 1.27 1.27)
				)
				(justify right)
			)
		)
		(property "Value" "C_1u_0402"
			(at 339.09 11.43 0)
			(effects
				(font
					(size 1.27 1.27)
					(thickness 0.15)
				)
				(justify left bottom)
				(hide yes)
			)
		)
		(property "Footprint" "antmicro-footprints:C_0402_1005Metric"
			(at 341.63 11.43 0)
			(effects
				(font
					(size 1.27 1.27)
					(thickness 0.15)
				)
				(justify left bottom)
				(hide yes)
			)
		)
		(property "Datasheet" "https://product.tdk.com/en/search/capacitor/ceramic/mlcc/info?part_no=C1005X6S1A105K050BC"
			(at 344.17 11.43 0)
			(effects
				(font
					(size 1.27 1.27)
					(thickness 0.15)
				)
				(justify left bottom)
				(hide yes)
			)
		)
		(property "Description" ""
			(at 328.93 31.75 0)
			(effects
				(font
					(size 1.27 1.27)
				)
				(hide yes)
			)
		)
		(property "Manufacturer" "TDK"
			(at 349.25 11.43 0)
			(effects
				(font
					(size 1.27 1.27)
					(thickness 0.15)
				)
				(justify left bottom)
				(hide yes)
			)
		)
		(property "MPN" "C1005X6S1A105K050BC"
			(at 346.71 11.43 0)
			(effects
				(font
					(size 1.27 1.27)
					(thickness 0.15)
				)
				(justify left bottom)
				(hide yes)
			)
		)
		(property "Val" "1u"
			(at 329.565 31.115 90)
			(effects
				(font
					(size 1.27 1.27)
					(thickness 0.15)
				)
				(justify right)
			)
		)
		(property "License" "Apache-2.0"
			(at 351.79 11.43 0)
			(effects
				(font
					(size 1.27 1.27)
					(thickness 0.15)
				)
				(justify left bottom)
				(hide yes)
			)
		)
		(property "Author" "Antmicro"
			(at 354.33 11.43 0)
			(effects
				(font
					(size 1.27 1.27)
					(thickness 0.15)
				)
				(justify left bottom)
				(hide yes)
			)
		)
		(property "Voltage" ""
			(at 356.87 11.43 0)
			(effects
				(font
					(size 1.27 1.27)
				)
				(justify left bottom)
				(hide yes)
			)
		)
		(property "Dielectric" ""
			(at 359.41 11.43 0)
			(effects
				(font
					(size 1.27 1.27)
				)
				(justify left bottom)
				(hide yes)
			)
		)
		(pin "1"
		)
		(pin "2"
		)
		(instances
			(project "data-center-rdimm-ddr5-tester"
				(path ""
					(reference "C198")
					(unit 1)
				)
			)
		)
	)
	(symbol
		(lib_id "antmicroResistors0402:R_47k_0402")
		(at 171.45 262.89 90)
		(unit 1)
		(exclude_from_sim no)
		(in_bom yes)
		(on_board yes)
		(dnp no)
		(property "Reference" "R135"
			(at 170.18 259.08 90)
			(effects
				(font
					(size 1.27 1.27)
				)
				(justify left)
			)
		)
		(property "Value" "R_47k_0402"
			(at 184.15 242.57 0)
			(effects
				(font
					(size 1.27 1.27)
					(thickness 0.15)
				)
				(justify left bottom)
				(hide yes)
			)
		)
		(property "Footprint" "antmicro-footprints:R_0402_1005Metric"
			(at 186.69 242.57 0)
			(effects
				(font
					(size 1.27 1.27)
					(thickness 0.15)
				)
				(justify left bottom)
				(hide yes)
			)
		)
		(property "Datasheet" "https://www.bourns.com/docs/product-datasheets/cr.pdf"
			(at 189.23 242.57 0)
			(effects
				(font
					(size 1.27 1.27)
					(thickness 0.15)
				)
				(justify left bottom)
				(hide yes)
			)
		)
		(property "Description" ""
			(at 171.45 262.89 0)
			(effects
				(font
					(size 1.27 1.27)
				)
				(hide yes)
			)
		)
		(property "Manufacturer" "Bourns"
			(at 194.31 242.57 0)
			(effects
				(font
					(size 1.27 1.27)
					(thickness 0.15)
				)
				(justify left bottom)
				(hide yes)
			)
		)
		(property "MPN" "CR0402-FX-4702GLF"
			(at 191.77 242.57 0)
			(effects
				(font
					(size 1.27 1.27)
					(thickness 0.15)
				)
				(justify left bottom)
				(hide yes)
			)
		)
		(property "Val" "47k"
			(at 170.18 261.62 90)
			(effects
				(font
					(size 1.27 1.27)
					(thickness 0.15)
				)
				(justify left)
			)
		)
		(property "License" "Apache-2.0"
			(at 196.85 242.57 0)
			(effects
				(font
					(size 1.27 1.27)
					(thickness 0.15)
				)
				(justify left bottom)
				(hide yes)
			)
		)
		(property "Author" "Antmicro"
			(at 199.39 242.57 0)
			(effects
				(font
					(size 1.27 1.27)
					(thickness 0.15)
				)
				(justify left bottom)
				(hide yes)
			)
		)
		(property "Tolerance" "1%"
			(at 181.61 242.57 0)
			(effects
				(font
					(size 1.27 1.27)
				)
				(justify left bottom)
				(hide yes)
			)
		)
		(pin "1"
		)
		(pin "2"
		)
		(instances
			(project "data-center-rdimm-ddr5-tester"
				(path ""
					(reference "R135")
					(unit 1)
				)
			)
		)
	)
	(symbol
		(lib_id "antmicropower:GND")
		(at 226.06 105.41 0)
		(mirror y)
		(unit 1)
		(exclude_from_sim no)
		(in_bom yes)
		(on_board yes)
		(dnp no)
		(property "Reference" "#PWR0551"
			(at 226.06 111.76 0)
			(effects
				(font
					(size 1.27 1.27)
				)
				(hide yes)
			)
		)
		(property "Value" "GND"
			(at 223.901 109.22 0)
			(effects
				(font
					(size 1.27 1.27)
					(thickness 0.15)
				)
				(justify right)
			)
		)
		(property "Footprint" ""
			(at 217.17 113.03 0)
			(effects
				(font
					(size 1.27 1.27)
					(thickness 0.15)
				)
				(justify left bottom)
				(hide yes)
			)
		)
		(property "Datasheet" ""
			(at 217.17 118.11 0)
			(effects
				(font
					(size 1.27 1.27)
					(thickness 0.15)
				)
				(justify left bottom)
				(hide yes)
			)
		)
		(property "Description" ""
			(at 217.17 120.65 0)
			(effects
				(font
					(size 1.27 1.27)
				)
				(justify left bottom)
				(hide yes)
			)
		)
		(property "Author" "Antmicro"
			(at 217.17 113.03 0)
			(effects
				(font
					(size 1.27 1.27)
					(thickness 0.15)
				)
				(justify left bottom)
				(hide yes)
			)
		)
		(property "License" "Apache-2.0"
			(at 217.17 115.57 0)
			(effects
				(font
					(size 1.27 1.27)
					(thickness 0.15)
				)
				(justify left bottom)
				(hide yes)
			)
		)
		(pin "1"
		)
		(instances
			(project "data-center-rdimm-ddr5-tester"
				(path ""
					(reference "#PWR0551")
					(unit 1)
				)
			)
		)
	)
	(symbol
		(lib_id "antmicropower:GND")
		(at 167.64 196.85 0)
		(unit 1)
		(exclude_from_sim no)
		(in_bom yes)
		(on_board yes)
		(dnp no)
		(fields_autoplaced yes)
		(property "Reference" "#PWR0351"
			(at 167.64 203.2 0)
			(effects
				(font
					(size 1.27 1.27)
				)
				(hide yes)
			)
		)
		(property "Value" "GND"
			(at 165.735 201.295 0)
			(effects
				(font
					(size 1.27 1.27)
					(thickness 0.15)
				)
				(justify left bottom)
			)
		)
		(property "Footprint" ""
			(at 176.53 204.47 0)
			(effects
				(font
					(size 1.27 1.27)
					(thickness 0.15)
				)
				(justify left bottom)
				(hide yes)
			)
		)
		(property "Datasheet" ""
			(at 176.53 209.55 0)
			(effects
				(font
					(size 1.27 1.27)
					(thickness 0.15)
				)
				(justify left bottom)
				(hide yes)
			)
		)
		(property "Description" ""
			(at 167.64 196.85 0)
			(effects
				(font
					(size 1.27 1.27)
				)
				(hide yes)
			)
		)
		(property "Author" "Antmicro"
			(at 176.53 201.93 0)
			(effects
				(font
					(size 1.27 1.27)
					(thickness 0.15)
				)
				(justify left bottom)
				(hide yes)
			)
		)
		(property "License" "Apache-2.0"
			(at 176.53 204.47 0)
			(effects
				(font
					(size 1.27 1.27)
					(thickness 0.15)
				)
				(justify left bottom)
				(hide yes)
			)
		)
		(pin "1"
		)
		(instances
			(project "data-center-rdimm-ddr5-tester"
				(path ""
					(reference "#PWR0351")
					(unit 1)
				)
			)
		)
	)
	(symbol
		(lib_id "antmicroCapacitors0603:C_1u_25V_0603")
		(at 130.81 95.25 90)
		(unit 1)
		(exclude_from_sim no)
		(in_bom yes)
		(on_board yes)
		(dnp no)
		(property "Reference" "C180"
			(at 121.285 93.345 90)
			(effects
				(font
					(size 1.27 1.27)
				)
				(justify right)
			)
		)
		(property "Value" "C_1u_25V_0603"
			(at 140.97 74.93 0)
			(effects
				(font
					(size 1.27 1.27)
					(thickness 0.15)
				)
				(justify left bottom)
				(hide yes)
			)
		)
		(property "Footprint" "antmicro-footprints:C_0603_1608Metric"
			(at 143.51 74.93 0)
			(effects
				(font
					(size 1.27 1.27)
					(thickness 0.15)
				)
				(justify left bottom)
				(hide yes)
			)
		)
		(property "Datasheet" "https://product.samsungsem.com/mlcc/CL10A105KA8NNN.do"
			(at 146.05 74.93 0)
			(effects
				(font
					(size 1.27 1.27)
					(thickness 0.15)
				)
				(justify left bottom)
				(hide yes)
			)
		)
		(property "Description" ""
			(at 130.81 95.25 0)
			(effects
				(font
					(size 1.27 1.27)
				)
				(hide yes)
			)
		)
		(property "Manufacturer" "Samsung Electro-Mechanics"
			(at 151.13 74.93 0)
			(effects
				(font
					(size 1.27 1.27)
					(thickness 0.15)
				)
				(justify left bottom)
				(hide yes)
			)
		)
		(property "MPN" "CL10A105KA8NNNC"
			(at 148.59 74.93 0)
			(effects
				(font
					(size 1.27 1.27)
					(thickness 0.15)
				)
				(justify left bottom)
				(hide yes)
			)
		)
		(property "Val" "1u"
			(at 121.285 95.885 90)
			(effects
				(font
					(size 1.27 1.27)
					(thickness 0.15)
				)
				(justify right)
			)
		)
		(property "License" "Apache-2.0"
			(at 153.67 74.93 0)
			(effects
				(font
					(size 1.27 1.27)
					(thickness 0.15)
				)
				(justify left bottom)
				(hide yes)
			)
		)
		(property "Author" "Antmicro"
			(at 156.21 74.93 0)
			(effects
				(font
					(size 1.27 1.27)
					(thickness 0.15)
				)
				(justify left bottom)
				(hide yes)
			)
		)
		(property "Voltage" "25V"
			(at 158.75 74.93 0)
			(effects
				(font
					(size 1.27 1.27)
				)
				(justify left bottom)
				(hide yes)
			)
		)
		(property "Dielectric" ""
			(at 161.29 74.93 0)
			(effects
				(font
					(size 1.27 1.27)
				)
				(justify left bottom)
				(hide yes)
			)
		)
		(pin "1"
		)
		(pin "2"
		)
		(instances
			(project "data-center-rdimm-ddr5-tester"
				(path ""
					(reference "C180")
					(unit 1)
				)
			)
		)
	)
	(symbol
		(lib_id "antmicropower:GND")
		(at 86.36 101.6 0)
		(unit 1)
		(exclude_from_sim no)
		(in_bom yes)
		(on_board yes)
		(dnp no)
		(property "Reference" "#PWR0293"
			(at 86.36 107.95 0)
			(effects
				(font
					(size 1.27 1.27)
				)
				(hide yes)
			)
		)
		(property "Value" "GND"
			(at 84.455 106.045 0)
			(effects
				(font
					(size 1.27 1.27)
					(thickness 0.15)
				)
				(justify left bottom)
			)
		)
		(property "Footprint" ""
			(at 95.25 109.22 0)
			(effects
				(font
					(size 1.27 1.27)
					(thickness 0.15)
				)
				(justify left bottom)
				(hide yes)
			)
		)
		(property "Datasheet" ""
			(at 95.25 114.3 0)
			(effects
				(font
					(size 1.27 1.27)
					(thickness 0.15)
				)
				(justify left bottom)
				(hide yes)
			)
		)
		(property "Description" ""
			(at 86.36 101.6 0)
			(effects
				(font
					(size 1.27 1.27)
				)
				(hide yes)
			)
		)
		(property "Author" "Antmicro"
			(at 95.25 106.68 0)
			(effects
				(font
					(size 1.27 1.27)
					(thickness 0.15)
				)
				(justify left bottom)
				(hide yes)
			)
		)
		(property "License" "Apache-2.0"
			(at 95.25 109.22 0)
			(effects
				(font
					(size 1.27 1.27)
					(thickness 0.15)
				)
				(justify left bottom)
				(hide yes)
			)
		)
		(pin "1"
		)
		(instances
			(project "data-center-rdimm-ddr5-tester"
				(path ""
					(reference "#PWR0293")
					(unit 1)
				)
			)
		)
	)
	(symbol
		(lib_id "antmicroTransistorsFETsMOSFETsSingle:BSS138PW")
		(at 222.25 189.23 0)
		(unit 1)
		(exclude_from_sim no)
		(in_bom yes)
		(on_board yes)
		(dnp no)
		(fields_autoplaced yes)
		(property "Reference" "Q17"
			(at 233.68 185.42 0)
			(effects
				(font
					(size 1.27 1.27)
					(thickness 0.15)
				)
				(justify left)
			)
		)
		(property "Value" "BSS138PW"
			(at 245.11 198.12 0)
			(effects
				(font
					(size 1.27 1.27)
					(thickness 0.15)
				)
				(justify left bottom)
				(hide yes)
			)
		)
		(property "Footprint" "antmicro-footprints:SC70-3"
			(at 245.11 200.66 0)
			(effects
				(font
					(size 1.27 1.27)
					(thickness 0.15)
				)
				(justify left bottom)
				(hide yes)
			)
		)
		(property "Datasheet" "https://assets.nexperia.com/documents/data-sheet/BSS138PW.pdf"
			(at 245.11 203.2 0)
			(effects
				(font
					(size 1.27 1.27)
					(thickness 0.15)
				)
				(justify left bottom)
				(hide yes)
			)
		)
		(property "Description" ""
			(at 222.25 189.23 0)
			(effects
				(font
					(size 1.27 1.27)
				)
				(hide yes)
			)
		)
		(property "MPN" "BSS138PW"
			(at 233.68 187.96 0)
			(effects
				(font
					(size 1.27 1.27)
					(thickness 0.15)
				)
				(justify left)
			)
		)
		(property "Manufacturer" "Nexperia"
			(at 245.11 208.28 0)
			(effects
				(font
					(size 1.27 1.27)
					(thickness 0.15)
				)
				(justify left bottom)
				(hide yes)
			)
		)
		(property "Author" "Antmicro"
			(at 245.11 210.82 0)
			(effects
				(font
					(size 1.27 1.27)
					(thickness 0.15)
				)
				(justify left bottom)
				(hide yes)
			)
		)
		(property "License" "Apache-2.0"
			(at 245.11 213.36 0)
			(effects
				(font
					(size 1.27 1.27)
					(thickness 0.15)
				)
				(justify left bottom)
				(hide yes)
			)
		)
		(pin "1"
		)
		(pin "3"
		)
		(pin "2"
		)
		(instances
			(project "data-center-rdimm-ddr5-tester"
				(path ""
					(reference "Q17")
					(unit 1)
				)
			)
		)
	)
	(symbol
		(lib_id "antmicropower:+3V3_AON")
		(at 198.12 166.37 0)
		(mirror y)
		(unit 1)
		(exclude_from_sim no)
		(in_bom yes)
		(on_board yes)
		(dnp no)
		(property "Reference" "#PWR0368"
			(at 198.12 170.18 0)
			(effects
				(font
					(size 1.27 1.27)
				)
				(hide yes)
			)
		)
		(property "Value" "+3V3_AON"
			(at 198.12 162.56 0)
			(effects
				(font
					(size 1.27 1.27)
				)
			)
		)
		(property "Footprint" ""
			(at 198.12 166.37 0)
			(effects
				(font
					(size 1.27 1.27)
				)
				(hide yes)
			)
		)
		(property "Datasheet" ""
			(at 198.12 166.37 0)
			(effects
				(font
					(size 1.27 1.27)
				)
				(hide yes)
			)
		)
		(property "Description" ""
			(at 198.12 166.37 0)
			(effects
				(font
					(size 1.27 1.27)
				)
				(hide yes)
			)
		)
		(pin "1"
		)
		(instances
			(project "data-center-rdimm-ddr5-tester"
				(path ""
					(reference "#PWR0368")
					(unit 1)
				)
			)
		)
	)
	(symbol
		(lib_id "antmicroCapacitors0402:C_100n_0402")
		(at 233.68 104.14 270)
		(mirror x)
		(unit 1)
		(exclude_from_sim no)
		(in_bom yes)
		(on_board yes)
		(dnp no)
		(property "Reference" "C330"
			(at 233.934 99.8219 90)
			(effects
				(font
					(size 1.27 1.27)
				)
				(justify left)
			)
		)
		(property "Value" "C_100n_0402"
			(at 223.52 83.82 0)
			(effects
				(font
					(size 1.27 1.27)
					(thickness 0.15)
				)
				(justify left bottom)
				(hide yes)
			)
		)
		(property "Footprint" "antmicro-footprints:C_0402_1005Metric"
			(at 220.98 83.82 0)
			(effects
				(font
					(size 1.27 1.27)
					(thickness 0.15)
				)
				(justify left bottom)
				(hide yes)
			)
		)
		(property "Datasheet" "https://www.murata.com/products/productdetail?partno=GRM155R61H104KE14%23"
			(at 218.44 83.82 0)
			(effects
				(font
					(size 1.27 1.27)
					(thickness 0.15)
				)
				(justify left bottom)
				(hide yes)
			)
		)
		(property "Description" ""
			(at 233.68 104.14 0)
			(effects
				(font
					(size 1.27 1.27)
				)
			)
		)
		(property "Manufacturer" "Murata"
			(at 213.36 83.82 0)
			(effects
				(font
					(size 1.27 1.27)
					(thickness 0.15)
				)
				(justify left bottom)
				(hide yes)
			)
		)
		(property "MPN" "GRM155R61H104KE14D"
			(at 215.9 83.82 0)
			(effects
				(font
					(size 1.27 1.27)
					(thickness 0.15)
				)
				(justify left bottom)
				(hide yes)
			)
		)
		(property "Val" "100n"
			(at 234.188 103.632 90)
			(effects
				(font
					(size 1.27 1.27)
					(thickness 0.15)
				)
				(justify left)
			)
		)
		(property "License" "Apache-2.0"
			(at 210.82 83.82 0)
			(effects
				(font
					(size 1.27 1.27)
					(thickness 0.15)
				)
				(justify left bottom)
				(hide yes)
			)
		)
		(property "Author" "Antmicro"
			(at 208.28 83.82 0)
			(effects
				(font
					(size 1.27 1.27)
					(thickness 0.15)
				)
				(justify left bottom)
				(hide yes)
			)
		)
		(property "Voltage" "50V"
			(at 205.74 83.82 0)
			(effects
				(font
					(size 1.27 1.27)
				)
				(justify left bottom)
				(hide yes)
			)
		)
		(property "Dielectric" "X5R"
			(at 203.2 83.82 0)
			(effects
				(font
					(size 1.27 1.27)
				)
				(justify left bottom)
				(hide yes)
			)
		)
		(pin "1"
		)
		(pin "2"
		)
		(instances
			(project "data-center-rdimm-ddr5-tester"
				(path ""
					(reference "C330")
					(unit 1)
				)
			)
		)
	)
	(symbol
		(lib_id "antmicropower:+3V3_AON")
		(at 60.96 214.63 0)
		(mirror y)
		(unit 1)
		(exclude_from_sim no)
		(in_bom yes)
		(on_board yes)
		(dnp no)
		(property "Reference" "#PWR0294"
			(at 60.96 218.44 0)
			(effects
				(font
					(size 1.27 1.27)
				)
				(hide yes)
			)
		)
		(property "Value" "+3V3_AON"
			(at 54.61 210.82 0)
			(effects
				(font
					(size 1.27 1.27)
				)
			)
		)
		(property "Footprint" ""
			(at 60.96 214.63 0)
			(effects
				(font
					(size 1.27 1.27)
				)
				(hide yes)
			)
		)
		(property "Datasheet" ""
			(at 60.96 214.63 0)
			(effects
				(font
					(size 1.27 1.27)
				)
				(hide yes)
			)
		)
		(property "Description" ""
			(at 60.96 214.63 0)
			(effects
				(font
					(size 1.27 1.27)
				)
				(hide yes)
			)
		)
		(pin "1"
		)
		(instances
			(project "data-center-rdimm-ddr5-tester"
				(path ""
					(reference "#PWR0294")
					(unit 1)
				)
			)
		)
	)
	(symbol
		(lib_id "antmicroPMICORControllersIdealDiodes:LTC4412IS6")
		(at 87.63 87.63 0)
		(unit 1)
		(exclude_from_sim no)
		(in_bom yes)
		(on_board yes)
		(dnp no)
		(fields_autoplaced yes)
		(property "Reference" "U18"
			(at 96.52 80.01 0)
			(effects
				(font
					(size 1.27 1.27)
					(thickness 0.15)
				)
			)
		)
		(property "Value" "LTC4412IS6"
			(at 119.38 92.71 0)
			(effects
				(font
					(size 1.27 1.27)
					(thickness 0.15)
				)
				(justify left bottom)
				(hide yes)
			)
		)
		(property "Footprint" "antmicro-footprints:SOT-23-6"
			(at 119.38 95.25 0)
			(effects
				(font
					(size 1.27 1.27)
					(thickness 0.15)
				)
				(justify left bottom)
				(hide yes)
			)
		)
		(property "Datasheet" "https://www.mouser.com/datasheet/2/308/NCV8187_D-1813214.pdf"
			(at 119.38 97.79 0)
			(effects
				(font
					(size 1.27 1.27)
					(thickness 0.15)
				)
				(justify left bottom)
				(hide yes)
			)
		)
		(property "Description" ""
			(at 87.63 87.63 0)
			(effects
				(font
					(size 1.27 1.27)
				)
				(hide yes)
			)
		)
		(property "MPN" "LTC4412IS6#TRMPBF"
			(at 96.52 82.55 0)
			(effects
				(font
					(size 1.27 1.27)
					(thickness 0.15)
				)
			)
		)
		(property "Manufacturer" "Analog Devices"
			(at 119.38 102.87 0)
			(effects
				(font
					(size 1.27 1.27)
					(thickness 0.15)
				)
				(justify left bottom)
				(hide yes)
			)
		)
		(property "Author" "Antmicro"
			(at 119.38 105.41 0)
			(effects
				(font
					(size 1.27 1.27)
					(thickness 0.15)
				)
				(justify left bottom)
				(hide yes)
			)
		)
		(property "License" "Apache-2.0"
			(at 119.38 107.95 0)
			(effects
				(font
					(size 1.27 1.27)
					(thickness 0.15)
				)
				(justify left bottom)
				(hide yes)
			)
		)
		(pin "2"
		)
		(pin "3"
		)
		(pin "5"
		)
		(pin "1"
		)
		(pin "6"
		)
		(pin "4"
		)
		(instances
			(project "data-center-rdimm-ddr5-tester"
				(path ""
					(reference "U18")
					(unit 1)
				)
			)
		)
	)
	(symbol
		(lib_id "antmicropower:GND")
		(at 307.34 87.63 0)
		(unit 1)
		(exclude_from_sim no)
		(in_bom yes)
		(on_board yes)
		(dnp no)
		(fields_autoplaced yes)
		(property "Reference" "#PWR0545"
			(at 307.34 93.98 0)
			(effects
				(font
					(size 1.27 1.27)
				)
				(hide yes)
			)
		)
		(property "Value" "GND"
			(at 305.435 92.075 0)
			(effects
				(font
					(size 1.27 1.27)
					(thickness 0.15)
				)
				(justify left bottom)
			)
		)
		(property "Footprint" ""
			(at 316.23 95.25 0)
			(effects
				(font
					(size 1.27 1.27)
					(thickness 0.15)
				)
				(justify left bottom)
				(hide yes)
			)
		)
		(property "Datasheet" ""
			(at 316.23 100.33 0)
			(effects
				(font
					(size 1.27 1.27)
					(thickness 0.15)
				)
				(justify left bottom)
				(hide yes)
			)
		)
		(property "Description" ""
			(at 307.34 87.63 0)
			(effects
				(font
					(size 1.27 1.27)
				)
				(hide yes)
			)
		)
		(property "Author" "Antmicro"
			(at 316.23 92.71 0)
			(effects
				(font
					(size 1.27 1.27)
					(thickness 0.15)
				)
				(justify left bottom)
				(hide yes)
			)
		)
		(property "License" "Apache-2.0"
			(at 316.23 95.25 0)
			(effects
				(font
					(size 1.27 1.27)
					(thickness 0.15)
				)
				(justify left bottom)
				(hide yes)
			)
		)
		(pin "1"
		)
		(instances
			(project "data-center-rdimm-ddr5-tester"
				(path ""
					(reference "#PWR0545")
					(unit 1)
				)
			)
		)
	)
	(sheet
		(at 364.49 171.45)
		(size 30.48 17.78)
		(exclude_from_sim no)
		(in_bom yes)
		(on_board yes)
		(dnp no)
		(fields_autoplaced yes)
		(stroke
			(width 0.1524)
			(type solid)
		)
		(fill
			(color 0 0 0 0.0000)
		)
		(property "Sheetname" "DC-DC AUX, MGT"
			(at 364.49 170.7384 0)
			(effects
				(font
					(size 1.27 1.27)
				)
				(justify left bottom)
			)
		)
		(property "Sheetfile" "dc-dc-aux-mgt.kicad_sch"
			(at 364.49 189.8146 0)
			(effects
				(font
					(size 1.27 1.27)
				)
				(justify left top)
			)
		)
		(pin "EN2" input
			(at 364.49 173.99 180)
			(effects
				(font
					(size 1.27 1.27)
				)
				(justify left)
			)
		)
		(pin "PWR.SCL" input
			(at 364.49 186.69 180)
			(effects
				(font
					(size 1.27 1.27)
				)
				(justify left)
			)
		)
		(pin "PWR.SDA" input
			(at 364.49 184.15 180)
			(effects
				(font
					(size 1.27 1.27)
				)
				(justify left)
			)
		)
		(instances
			(project "data-center-rdimm-ddr5-tester"
				(path ""
					(page "19")
				)
			)
		)
	)
	(sheet
		(at 364.49 143.51)
		(size 30.48 17.78)
		(exclude_from_sim no)
		(in_bom yes)
		(on_board yes)
		(dnp no)
		(fields_autoplaced yes)
		(stroke
			(width 0.1524)
			(type solid)
		)
		(fill
			(color 0 0 0 0.0000)
		)
		(property "Sheetname" "DC-DC VCCINT"
			(at 364.49 142.7984 0)
			(effects
				(font
					(size 1.27 1.27)
				)
				(justify left bottom)
			)
		)
		(property "Sheetfile" "dc-dc-vccint.kicad_sch"
			(at 364.49 161.8746 0)
			(effects
				(font
					(size 1.27 1.27)
				)
				(justify left top)
			)
		)
		(pin "EN1" input
			(at 364.49 146.05 180)
			(effects
				(font
					(size 1.27 1.27)
				)
				(justify left)
			)
		)
		(pin "PWR.SDA" input
			(at 364.49 157.48 180)
			(effects
				(font
					(size 1.27 1.27)
				)
				(justify left)
			)
		)
		(pin "PWR.SCL" input
			(at 364.49 160.02 180)
			(effects
				(font
					(size 1.27 1.27)
				)
				(justify left)
			)
		)
		(instances
			(project "data-center-rdimm-ddr5-tester"
				(path ""
					(page "18")
				)
			)
		)
	)
	(sheet
		(at 364.49 198.12)
		(size 30.48 17.78)
		(exclude_from_sim no)
		(in_bom yes)
		(on_board yes)
		(dnp no)
		(fields_autoplaced yes)
		(stroke
			(width 0.1524)
			(type solid)
		)
		(fill
			(color 0 0 0 0.0000)
		)
		(property "Sheetname" "DC-DC IO"
			(at 364.49 197.4084 0)
			(effects
				(font
					(size 1.27 1.27)
				)
				(justify left bottom)
			)
		)
		(property "Sheetfile" "dc-dc-io.kicad_sch"
			(at 364.49 216.4846 0)
			(effects
				(font
					(size 1.27 1.27)
				)
				(justify left top)
			)
		)
		(pin "EN3" input
			(at 364.49 200.66 180)
			(effects
				(font
					(size 1.27 1.27)
				)
				(justify left)
			)
		)
		(pin "PWR.SDA" input
			(at 364.49 208.28 180)
			(effects
				(font
					(size 1.27 1.27)
				)
				(justify left)
			)
		)
		(pin "QDCDC2_SCL" input
			(at 364.49 213.36 180)
			(effects
				(font
					(size 1.27 1.27)
				)
				(justify left)
			)
		)
		(pin "PWR.SCL" input
			(at 364.49 210.82 180)
			(effects
				(font
					(size 1.27 1.27)
				)
				(justify left)
			)
		)
		(instances
			(project "data-center-rdimm-ddr5-tester"
				(path ""
					(page "20")
				)
			)
		)
	)
)
